(kicad_sch
	(version 20250114)
	(generator "eeschema")
	(generator_version "9.0")
	(paper "A3")
	(title_block
		(title "SDI-MIPI Video Converter")
		(date "2023-10-12")
		(rev "1.1.4")
		(comment 1 "www.antmicro.com")
		(comment 2 "Antmicro Ltd.")
	)
	(text "DDR MEMORY TERMINATION SUPPLY"
		(exclude_from_sim no)
		(at 26.67 115.57 0)
		(effects
			(font
				(size 3 3)
			)
			(justify left bottom)
		)
	)
	(text "300mA max"
		(exclude_from_sim no)
		(at 334.01 190.5 0)
		(effects
			(font
				(size 1.27 1.27)
			)
			(justify left bottom)
		)
	)
	(text "INTERNAL\nPOWER"
		(exclude_from_sim no)
		(at 220.98 266.7 0)
		(effects
			(font
				(size 1.27 1.27)
			)
			(justify left bottom)
		)
	)
	(text "LDOs\n"
		(exclude_from_sim no)
		(at 318.77 143.51 0)
		(effects
			(font
				(size 3 3)
			)
			(justify left bottom)
		)
	)
	(text "Ideal diode"
		(exclude_from_sim no)
		(at 102.87 24.13 0)
		(effects
			(font
				(size 2 2)
			)
			(justify left bottom)
		)
	)
	(text "2.0A max\n86% eff\n11mV est. ripple\n"
		(exclude_from_sim no)
		(at 339.09 104.14 0)
		(effects
			(font
				(size 1.27 1.27)
			)
			(justify left bottom)
		)
	)
	(text "Nominal currents are lower than rated"
		(exclude_from_sim no)
		(at 351.79 132.715 0)
		(effects
			(font
				(size 1.27 1.27)
			)
			(justify left bottom)
		)
	)
	(text "300mA max"
		(exclude_from_sim no)
		(at 334.01 224.79 0)
		(effects
			(font
				(size 1.27 1.27)
			)
			(justify left bottom)
		)
	)
	(text "2.0A max\n93% eff\n26mV est. ripple\n"
		(exclude_from_sim no)
		(at 341.63 38.1 0)
		(effects
			(font
				(size 1.27 1.27)
			)
			(justify left bottom)
		)
	)
	(text "Sense\n"
		(exclude_from_sim no)
		(at 92.71 133.35 0)
		(effects
			(font
				(size 1.27 1.27)
			)
			(justify left bottom)
		)
	)
	(text "SUPPLY SELECTION"
		(exclude_from_sim no)
		(at 49.53 17.78 0)
		(effects
			(font
				(size 3 3)
			)
			(justify left bottom)
		)
	)
	(text "Open collector outputs\npull down when no voltage on\none of the rails"
		(exclude_from_sim no)
		(at 135.89 248.92 0)
		(effects
			(font
				(size 1.27 1.27)
			)
			(justify left bottom)
		)
	)
	(text "CONVERTERS"
		(exclude_from_sim no)
		(at 311.15 19.05 0)
		(effects
			(font
				(size 3 3)
			)
			(justify left bottom)
		)
	)
	(text "5V POWER"
		(exclude_from_sim no)
		(at 242.57 265.43 0)
		(effects
			(font
				(size 1.27 1.27)
			)
			(justify left bottom)
		)
	)
	(text "USB-C takes precedence\nover power via FFC"
		(exclude_from_sim no)
		(at 13.97 109.22 0)
		(effects
			(font
				(size 2 2)
			)
			(justify left bottom)
		)
	)
	(text "PS BLOCK DIAGRAM"
		(exclude_from_sim no)
		(at 170.18 17.78 0)
		(effects
			(font
				(size 3 3)
			)
			(justify left bottom)
		)
	)
	(text "TEST POINTS"
		(exclude_from_sim no)
		(at 224.79 176.53 0)
		(effects
			(font
				(size 3 3)
			)
			(justify left bottom)
		)
	)
	(text "2.0A max\n86% eff\n10mV est. ripple\n"
		(exclude_from_sim no)
		(at 340.36 71.12 0)
		(effects
			(font
				(size 1.27 1.27)
			)
			(justify left bottom)
		)
	)
	(text "300mA max"
		(exclude_from_sim no)
		(at 335.28 154.94 0)
		(effects
			(font
				(size 1.27 1.27)
			)
			(justify left bottom)
		)
	)
	(text "POWER INDICATORS"
		(exclude_from_sim no)
		(at 67.31 176.53 0)
		(effects
			(font
				(size 3 3)
			)
			(justify left bottom)
		)
	)
	(junction
		(at 29.21 204.47)
		(diameter 0)
		(color 0 0 0 0)
	)
	(junction
		(at 355.6 72.39)
		(diameter 0)
		(color 0 0 0 0)
	)
	(junction
		(at 167.64 250.19)
		(diameter 0)
		(color 0 0 0 0)
	)
	(junction
		(at 133.35 250.19)
		(diameter 0)
		(color 0 0 0 0)
	)
	(junction
		(at 91.44 54.61)
		(diameter 0)
		(color 0 0 0 0)
	)
	(junction
		(at 308.61 196.85)
		(diameter 0)
		(color 0 0 0 0)
	)
	(junction
		(at 345.44 156.21)
		(diameter 0)
		(color 0 0 0 0)
	)
	(junction
		(at 345.44 166.37)
		(diameter 0)
		(color 0 0 0 0)
	)
	(junction
		(at 367.03 72.39)
		(diameter 0)
		(color 0 0 0 0)
	)
	(junction
		(at 297.18 196.85)
		(diameter 0)
		(color 0 0 0 0)
	)
	(junction
		(at 113.03 77.47)
		(diameter 0)
		(color 0 0 0 0)
	)
	(junction
		(at 229.87 232.41)
		(diameter 0)
		(color 0 0 0 0)
	)
	(junction
		(at 320.04 39.37)
		(diameter 0)
		(color 0 0 0 0)
	)
	(junction
		(at 318.77 105.41)
		(diameter 0)
		(color 0 0 0 0)
	)
	(junction
		(at 377.19 72.39)
		(diameter 0)
		(color 0 0 0 0)
	)
	(junction
		(at 73.66 86.36)
		(diameter 0)
		(color 0 0 0 0)
	)
	(junction
		(at 46.99 77.47)
		(diameter 0)
		(color 0 0 0 0)
	)
	(junction
		(at 345.44 226.06)
		(diameter 0)
		(color 0 0 0 0)
	)
	(junction
		(at 359.41 191.77)
		(diameter 0)
		(color 0 0 0 0)
	)
	(junction
		(at 201.93 250.19)
		(diameter 0)
		(color 0 0 0 0)
	)
	(junction
		(at 377.19 105.41)
		(diameter 0)
		(color 0 0 0 0)
	)
	(junction
		(at 53.34 140.97)
		(diameter 0)
		(color 0 0 0 0)
	)
	(junction
		(at 297.18 231.14)
		(diameter 0)
		(color 0 0 0 0)
	)
	(junction
		(at 109.22 135.89)
		(diameter 0)
		(color 0 0 0 0)
	)
	(junction
		(at 71.12 205.74)
		(diameter 0)
		(color 0 0 0 0)
	)
	(junction
		(at 38.1 77.47)
		(diameter 0)
		(color 0 0 0 0)
	)
	(junction
		(at 388.62 105.41)
		(diameter 0)
		(color 0 0 0 0)
	)
	(junction
		(at 355.6 39.37)
		(diameter 0)
		(color 0 0 0 0)
	)
	(junction
		(at 100.33 26.67)
		(diameter 0)
		(color 0 0 0 0)
	)
	(junction
		(at 123.19 77.47)
		(diameter 0)
		(color 0 0 0 0)
	)
	(junction
		(at 337.82 49.53)
		(diameter 0)
		(color 0 0 0 0)
	)
	(junction
		(at 73.66 77.47)
		(diameter 0)
		(color 0 0 0 0)
	)
	(junction
		(at 48.26 133.35)
		(diameter 0)
		(color 0 0 0 0)
	)
	(junction
		(at 377.19 39.37)
		(diameter 0)
		(color 0 0 0 0)
	)
	(junction
		(at 101.6 195.58)
		(diameter 0)
		(color 0 0 0 0)
	)
	(junction
		(at 345.44 201.93)
		(diameter 0)
		(color 0 0 0 0)
	)
	(junction
		(at 336.55 105.41)
		(diameter 0)
		(color 0 0 0 0)
	)
	(junction
		(at 53.34 146.05)
		(diameter 0)
		(color 0 0 0 0)
	)
	(junction
		(at 297.18 161.29)
		(diameter 0)
		(color 0 0 0 0)
	)
	(junction
		(at 359.41 226.06)
		(diameter 0)
		(color 0 0 0 0)
	)
	(junction
		(at 336.55 115.57)
		(diameter 0)
		(color 0 0 0 0)
	)
	(junction
		(at 337.82 39.37)
		(diameter 0)
		(color 0 0 0 0)
	)
	(junction
		(at 99.06 135.89)
		(diameter 0)
		(color 0 0 0 0)
	)
	(junction
		(at 269.24 72.39)
		(diameter 0)
		(color 0 0 0 0)
	)
	(junction
		(at 336.55 82.55)
		(diameter 0)
		(color 0 0 0 0)
	)
	(junction
		(at 99.06 250.19)
		(diameter 0)
		(color 0 0 0 0)
	)
	(junction
		(at 29.21 185.42)
		(diameter 0)
		(color 0 0 0 0)
	)
	(junction
		(at 71.12 186.69)
		(diameter 0)
		(color 0 0 0 0)
	)
	(junction
		(at 218.44 250.19)
		(diameter 0)
		(color 0 0 0 0)
	)
	(junction
		(at 59.69 26.67)
		(diameter 0)
		(color 0 0 0 0)
	)
	(junction
		(at 345.44 191.77)
		(diameter 0)
		(color 0 0 0 0)
	)
	(junction
		(at 359.41 156.21)
		(diameter 0)
		(color 0 0 0 0)
	)
	(junction
		(at 40.64 135.89)
		(diameter 0)
		(color 0 0 0 0)
	)
	(junction
		(at 367.03 39.37)
		(diameter 0)
		(color 0 0 0 0)
	)
	(junction
		(at 345.44 236.22)
		(diameter 0)
		(color 0 0 0 0)
	)
	(junction
		(at 388.62 72.39)
		(diameter 0)
		(color 0 0 0 0)
	)
	(junction
		(at 308.61 161.29)
		(diameter 0)
		(color 0 0 0 0)
	)
	(junction
		(at 388.62 39.37)
		(diameter 0)
		(color 0 0 0 0)
	)
	(junction
		(at 27.94 129.54)
		(diameter 0)
		(color 0 0 0 0)
	)
	(junction
		(at 59.69 96.52)
		(diameter 0)
		(color 0 0 0 0)
	)
	(junction
		(at 365.76 105.41)
		(diameter 0)
		(color 0 0 0 0)
	)
	(junction
		(at 355.6 105.41)
		(diameter 0)
		(color 0 0 0 0)
	)
	(junction
		(at 46.99 88.9)
		(diameter 0)
		(color 0 0 0 0)
	)
	(junction
		(at 336.55 72.39)
		(diameter 0)
		(color 0 0 0 0)
	)
	(junction
		(at 269.24 105.41)
		(diameter 0)
		(color 0 0 0 0)
	)
	(junction
		(at 86.36 52.07)
		(diameter 0)
		(color 0 0 0 0)
	)
	(junction
		(at 308.61 231.14)
		(diameter 0)
		(color 0 0 0 0)
	)
	(junction
		(at 318.77 72.39)
		(diameter 0)
		(color 0 0 0 0)
	)
	(junction
		(at 86.36 146.05)
		(diameter 0)
		(color 0 0 0 0)
	)
	(junction
		(at 77.47 26.67)
		(diameter 0)
		(color 0 0 0 0)
	)
	(junction
		(at 270.51 39.37)
		(diameter 0)
		(color 0 0 0 0)
	)
	(junction
		(at 109.22 133.35)
		(diameter 0)
		(color 0 0 0 0)
	)
	(no_connect
		(at 199.39 273.05)
	)
	(wire
		(pts
			(xy 39.37 26.67) (xy 59.69 26.67)
		)
		(stroke
			(width 0)
			(type default)
		)
	)
	(wire
		(pts
			(xy 101.6 195.58) (xy 113.03 195.58)
		)
		(stroke
			(width 0)
			(type default)
		)
	)
	(wire
		(pts
			(xy 317.5 44.45) (xy 320.04 44.45)
		)
		(stroke
			(width 0)
			(type default)
		)
	)
	(wire
		(pts
			(xy 367.03 85.09) (xy 367.03 91.44)
		)
		(stroke
			(width 0)
			(type default)
		)
	)
	(wire
		(pts
			(xy 73.66 86.36) (xy 83.82 86.36)
		)
		(stroke
			(width 0)
			(type default)
		)
	)
	(wire
		(pts
			(xy 53.34 140.97) (xy 53.34 146.05)
		)
		(stroke
			(width 0)
			(type default)
		)
	)
	(wire
		(pts
			(xy 85.09 267.97) (xy 85.09 270.51)
		)
		(stroke
			(width 0)
			(type default)
		)
	)
	(wire
		(pts
			(xy 377.19 39.37) (xy 377.19 46.99)
		)
		(stroke
			(width 0)
			(type default)
		)
	)
	(wire
		(pts
			(xy 345.44 201.93) (xy 345.44 204.47)
		)
		(stroke
			(width 0)
			(type default)
		)
	)
	(wire
		(pts
			(xy 288.29 50.8) (xy 288.29 49.53)
		)
		(stroke
			(width 0)
			(type default)
		)
	)
	(wire
		(pts
			(xy 241.3 232.41) (xy 241.3 241.3)
		)
		(stroke
			(width 0)
			(type default)
		)
	)
	(wire
		(pts
			(xy 270.51 48.26) (xy 270.51 50.8)
		)
		(stroke
			(width 0)
			(type default)
		)
	)
	(wire
		(pts
			(xy 345.44 236.22) (xy 345.44 238.76)
		)
		(stroke
			(width 0)
			(type default)
		)
	)
	(wire
		(pts
			(xy 355.6 39.37) (xy 355.6 46.99)
		)
		(stroke
			(width 0)
			(type default)
		)
	)
	(wire
		(pts
			(xy 284.48 77.47) (xy 288.29 77.47)
		)
		(stroke
			(width 0)
			(type default)
		)
	)
	(wire
		(pts
			(xy 332.74 166.37) (xy 345.44 166.37)
		)
		(stroke
			(width 0)
			(type default)
		)
	)
	(wire
		(pts
			(xy 355.6 72.39) (xy 355.6 80.01)
		)
		(stroke
			(width 0)
			(type default)
		)
	)
	(wire
		(pts
			(xy 48.26 133.35) (xy 48.26 137.16)
		)
		(stroke
			(width 0)
			(type default)
		)
	)
	(wire
		(pts
			(xy 398.78 39.37) (xy 402.59 39.37)
		)
		(stroke
			(width 0)
			(type default)
		)
	)
	(wire
		(pts
			(xy 308.61 236.22) (xy 311.15 236.22)
		)
		(stroke
			(width 0)
			(type default)
		)
	)
	(wire
		(pts
			(xy 59.69 102.87) (xy 59.69 104.14)
		)
		(stroke
			(width 0)
			(type default)
		)
	)
	(wire
		(pts
			(xy 113.03 87.63) (xy 113.03 88.9)
		)
		(stroke
			(width 0)
			(type default)
		)
	)
	(wire
		(pts
			(xy 123.19 77.47) (xy 123.19 81.28)
		)
		(stroke
			(width 0)
			(type default)
		)
	)
	(wire
		(pts
			(xy 19.05 204.47) (xy 29.21 204.47)
		)
		(stroke
			(width 0)
			(type default)
		)
	)
	(wire
		(pts
			(xy 154.94 273.05) (xy 143.51 273.05)
		)
		(stroke
			(width 0)
			(type default)
		)
	)
	(wire
		(pts
			(xy 86.36 50.8) (xy 86.36 52.07)
		)
		(stroke
			(width 0)
			(type default)
		)
	)
	(wire
		(pts
			(xy 269.24 72.39) (xy 288.29 72.39)
		)
		(stroke
			(width 0)
			(type default)
		)
	)
	(wire
		(pts
			(xy 316.23 236.22) (xy 317.5 236.22)
		)
		(stroke
			(width 0)
			(type default)
		)
	)
	(wire
		(pts
			(xy 332.74 231.14) (xy 337.82 231.14)
		)
		(stroke
			(width 0)
			(type default)
		)
	)
	(wire
		(pts
			(xy 40.64 147.32) (xy 40.64 148.59)
		)
		(stroke
			(width 0)
			(type default)
		)
	)
	(wire
		(pts
			(xy 297.18 196.85) (xy 297.18 199.39)
		)
		(stroke
			(width 0)
			(type default)
		)
	)
	(wire
		(pts
			(xy 66.04 96.52) (xy 59.69 96.52)
		)
		(stroke
			(width 0)
			(type default)
		)
	)
	(wire
		(pts
			(xy 337.82 39.37) (xy 355.6 39.37)
		)
		(stroke
			(width 0)
			(type default)
		)
	)
	(wire
		(pts
			(xy 377.19 85.09) (xy 377.19 91.44)
		)
		(stroke
			(width 0)
			(type default)
		)
	)
	(wire
		(pts
			(xy 218.44 250.19) (xy 218.44 254)
		)
		(stroke
			(width 0)
			(type default)
		)
	)
	(wire
		(pts
			(xy 308.61 161.29) (xy 317.5 161.29)
		)
		(stroke
			(width 0)
			(type default)
		)
	)
	(wire
		(pts
			(xy 46.99 77.47) (xy 73.66 77.47)
		)
		(stroke
			(width 0)
			(type default)
		)
	)
	(wire
		(pts
			(xy 180.34 231.14) (xy 189.23 231.14)
		)
		(stroke
			(width 0)
			(type default)
		)
	)
	(wire
		(pts
			(xy 269.24 114.3) (xy 269.24 116.84)
		)
		(stroke
			(width 0)
			(type default)
		)
	)
	(wire
		(pts
			(xy 53.34 127) (xy 53.34 140.97)
		)
		(stroke
			(width 0)
			(type default)
		)
	)
	(wire
		(pts
			(xy 100.33 26.67) (xy 100.33 36.83)
		)
		(stroke
			(width 0)
			(type default)
		)
	)
	(wire
		(pts
			(xy 266.7 105.41) (xy 269.24 105.41)
		)
		(stroke
			(width 0)
			(type default)
		)
	)
	(wire
		(pts
			(xy 306.07 231.14) (xy 308.61 231.14)
		)
		(stroke
			(width 0)
			(type default)
		)
	)
	(wire
		(pts
			(xy 101.6 195.58) (xy 101.6 199.39)
		)
		(stroke
			(width 0)
			(type default)
		)
	)
	(wire
		(pts
			(xy 40.64 135.89) (xy 40.64 142.24)
		)
		(stroke
			(width 0)
			(type default)
		)
	)
	(wire
		(pts
			(xy 119.38 267.97) (xy 119.38 270.51)
		)
		(stroke
			(width 0)
			(type default)
		)
	)
	(wire
		(pts
			(xy 111.76 231.14) (xy 120.65 231.14)
		)
		(stroke
			(width 0)
			(type default)
		)
	)
	(polyline
		(pts
			(xy 130.81 170.18) (xy 254 170.18)
		)
		(stroke
			(width 0)
			(type default)
		)
	)
	(wire
		(pts
			(xy 201.93 187.96) (xy 201.93 190.5)
		)
		(stroke
			(width 0)
			(type default)
		)
	)
	(wire
		(pts
			(xy 233.68 187.96) (xy 233.68 190.5)
		)
		(stroke
			(width 0)
			(type default)
		)
	)
	(polyline
		(pts
			(xy 254 12.7) (xy 254 284.48)
		)
		(stroke
			(width 0)
			(type default)
		)
	)
	(wire
		(pts
			(xy 345.44 163.83) (xy 345.44 166.37)
		)
		(stroke
			(width 0)
			(type default)
		)
	)
	(wire
		(pts
			(xy 388.62 105.41) (xy 394.97 105.41)
		)
		(stroke
			(width 0)
			(type default)
		)
	)
	(wire
		(pts
			(xy 354.33 191.77) (xy 359.41 191.77)
		)
		(stroke
			(width 0)
			(type default)
		)
	)
	(wire
		(pts
			(xy 123.19 86.36) (xy 123.19 87.63)
		)
		(stroke
			(width 0)
			(type default)
		)
	)
	(wire
		(pts
			(xy 86.36 148.59) (xy 86.36 146.05)
		)
		(stroke
			(width 0)
			(type default)
		)
	)
	(wire
		(pts
			(xy 332.74 196.85) (xy 337.82 196.85)
		)
		(stroke
			(width 0)
			(type default)
		)
	)
	(wire
		(pts
			(xy 345.44 226.06) (xy 345.44 228.6)
		)
		(stroke
			(width 0)
			(type default)
		)
	)
	(wire
		(pts
			(xy 316.23 166.37) (xy 317.5 166.37)
		)
		(stroke
			(width 0)
			(type default)
		)
	)
	(wire
		(pts
			(xy 260.35 39.37) (xy 262.89 39.37)
		)
		(stroke
			(width 0)
			(type default)
		)
	)
	(wire
		(pts
			(xy 182.88 274.32) (xy 182.88 275.59)
		)
		(stroke
			(width 0)
			(type default)
		)
	)
	(polyline
		(pts
			(xy 130.81 10.16) (xy 130.81 170.18)
		)
		(stroke
			(width 0)
			(type default)
		)
	)
	(wire
		(pts
			(xy 377.19 118.11) (xy 377.19 124.46)
		)
		(stroke
			(width 0)
			(type default)
		)
	)
	(wire
		(pts
			(xy 227.33 187.96) (xy 227.33 190.5)
		)
		(stroke
			(width 0)
			(type default)
		)
	)
	(wire
		(pts
			(xy 308.61 77.47) (xy 311.15 77.47)
		)
		(stroke
			(width 0)
			(type default)
		)
	)
	(wire
		(pts
			(xy 316.23 201.93) (xy 317.5 201.93)
		)
		(stroke
			(width 0)
			(type default)
		)
	)
	(wire
		(pts
			(xy 309.88 39.37) (xy 320.04 39.37)
		)
		(stroke
			(width 0)
			(type default)
		)
	)
	(wire
		(pts
			(xy 77.47 231.14) (xy 86.36 231.14)
		)
		(stroke
			(width 0)
			(type default)
		)
	)
	(wire
		(pts
			(xy 153.67 267.97) (xy 153.67 270.51)
		)
		(stroke
			(width 0)
			(type default)
		)
	)
	(wire
		(pts
			(xy 320.04 39.37) (xy 325.12 39.37)
		)
		(stroke
			(width 0)
			(type default)
		)
	)
	(wire
		(pts
			(xy 269.24 81.28) (xy 269.24 83.82)
		)
		(stroke
			(width 0)
			(type default)
		)
	)
	(wire
		(pts
			(xy 120.65 77.47) (xy 123.19 77.47)
		)
		(stroke
			(width 0)
			(type default)
		)
	)
	(wire
		(pts
			(xy 318.77 77.47) (xy 318.77 72.39)
		)
		(stroke
			(width 0)
			(type default)
		)
	)
	(wire
		(pts
			(xy 111.76 228.6) (xy 111.76 231.14)
		)
		(stroke
			(width 0)
			(type default)
		)
	)
	(wire
		(pts
			(xy 91.44 54.61) (xy 91.44 55.88)
		)
		(stroke
			(width 0)
			(type default)
		)
	)
	(wire
		(pts
			(xy 109.22 137.16) (xy 109.22 135.89)
		)
		(stroke
			(width 0)
			(type default)
		)
	)
	(wire
		(pts
			(xy 29.21 185.42) (xy 29.21 194.31)
		)
		(stroke
			(width 0)
			(type default)
		)
	)
	(wire
		(pts
			(xy 119.38 270.51) (xy 120.65 270.51)
		)
		(stroke
			(width 0)
			(type default)
		)
	)
	(wire
		(pts
			(xy 83.82 86.36) (xy 83.82 83.82)
		)
		(stroke
			(width 0)
			(type default)
		)
	)
	(wire
		(pts
			(xy 73.66 100.33) (xy 73.66 104.14)
		)
		(stroke
			(width 0)
			(type default)
		)
	)
	(wire
		(pts
			(xy 53.34 154.94) (xy 53.34 156.21)
		)
		(stroke
			(width 0)
			(type default)
		)
	)
	(wire
		(pts
			(xy 267.97 39.37) (xy 270.51 39.37)
		)
		(stroke
			(width 0)
			(type default)
		)
	)
	(wire
		(pts
			(xy 71.12 198.12) (xy 71.12 205.74)
		)
		(stroke
			(width 0)
			(type default)
		)
	)
	(wire
		(pts
			(xy 146.05 231.14) (xy 154.94 231.14)
		)
		(stroke
			(width 0)
			(type default)
		)
	)
	(wire
		(pts
			(xy 259.08 105.41) (xy 261.62 105.41)
		)
		(stroke
			(width 0)
			(type default)
		)
	)
	(wire
		(pts
			(xy 270.51 39.37) (xy 270.51 43.18)
		)
		(stroke
			(width 0)
			(type default)
		)
	)
	(wire
		(pts
			(xy 86.36 153.67) (xy 86.36 154.94)
		)
		(stroke
			(width 0)
			(type default)
		)
	)
	(wire
		(pts
			(xy 355.6 72.39) (xy 367.03 72.39)
		)
		(stroke
			(width 0)
			(type default)
		)
	)
	(wire
		(pts
			(xy 337.82 191.77) (xy 345.44 191.77)
		)
		(stroke
			(width 0)
			(type default)
		)
	)
	(wire
		(pts
			(xy 180.34 229.87) (xy 180.34 231.14)
		)
		(stroke
			(width 0)
			(type default)
		)
	)
	(wire
		(pts
			(xy 402.59 39.37) (xy 402.59 38.1)
		)
		(stroke
			(width 0)
			(type default)
		)
	)
	(wire
		(pts
			(xy 345.44 191.77) (xy 349.25 191.77)
		)
		(stroke
			(width 0)
			(type default)
		)
	)
	(wire
		(pts
			(xy 19.05 185.42) (xy 29.21 185.42)
		)
		(stroke
			(width 0)
			(type default)
		)
	)
	(wire
		(pts
			(xy 113.03 81.28) (xy 113.03 82.55)
		)
		(stroke
			(width 0)
			(type default)
		)
	)
	(wire
		(pts
			(xy 218.44 246.38) (xy 218.44 250.19)
		)
		(stroke
			(width 0)
			(type default)
		)
	)
	(wire
		(pts
			(xy 367.03 72.39) (xy 377.19 72.39)
		)
		(stroke
			(width 0)
			(type default)
		)
	)
	(wire
		(pts
			(xy 167.64 271.78) (xy 167.64 250.19)
		)
		(stroke
			(width 0)
			(type default)
		)
	)
	(wire
		(pts
			(xy 336.55 113.03) (xy 336.55 115.57)
		)
		(stroke
			(width 0)
			(type default)
		)
	)
	(wire
		(pts
			(xy 91.44 50.8) (xy 91.44 54.61)
		)
		(stroke
			(width 0)
			(type default)
		)
	)
	(wire
		(pts
			(xy 336.55 105.41) (xy 355.6 105.41)
		)
		(stroke
			(width 0)
			(type default)
		)
	)
	(wire
		(pts
			(xy 332.74 161.29) (xy 337.82 161.29)
		)
		(stroke
			(width 0)
			(type default)
		)
	)
	(wire
		(pts
			(xy 337.82 161.29) (xy 337.82 156.21)
		)
		(stroke
			(width 0)
			(type default)
		)
	)
	(wire
		(pts
			(xy 287.02 115.57) (xy 288.29 115.57)
		)
		(stroke
			(width 0)
			(type default)
		)
	)
	(wire
		(pts
			(xy 74.93 233.68) (xy 86.36 233.68)
		)
		(stroke
			(width 0)
			(type default)
		)
	)
	(wire
		(pts
			(xy 99.06 250.19) (xy 99.06 232.41)
		)
		(stroke
			(width 0)
			(type default)
		)
	)
	(wire
		(pts
			(xy 332.74 201.93) (xy 345.44 201.93)
		)
		(stroke
			(width 0)
			(type default)
		)
	)
	(wire
		(pts
			(xy 345.44 243.84) (xy 345.44 245.11)
		)
		(stroke
			(width 0)
			(type default)
		)
	)
	(polyline
		(pts
			(xy 12.7 170.18) (xy 130.81 170.18)
		)
		(stroke
			(width 0)
			(type default)
		)
	)
	(wire
		(pts
			(xy 107.95 273.05) (xy 120.65 273.05)
		)
		(stroke
			(width 0)
			(type default)
		)
	)
	(wire
		(pts
			(xy 337.82 39.37) (xy 337.82 41.91)
		)
		(stroke
			(width 0)
			(type default)
		)
	)
	(wire
		(pts
			(xy 19.05 198.12) (xy 19.05 204.47)
		)
		(stroke
			(width 0)
			(type default)
		)
	)
	(wire
		(pts
			(xy 40.64 133.35) (xy 48.26 133.35)
		)
		(stroke
			(width 0)
			(type default)
		)
	)
	(wire
		(pts
			(xy 107.95 233.68) (xy 120.65 233.68)
		)
		(stroke
			(width 0)
			(type default)
		)
	)
	(wire
		(pts
			(xy 109.22 130.81) (xy 109.22 133.35)
		)
		(stroke
			(width 0)
			(type default)
		)
	)
	(wire
		(pts
			(xy 367.03 72.39) (xy 367.03 80.01)
		)
		(stroke
			(width 0)
			(type default)
		)
	)
	(wire
		(pts
			(xy 345.44 226.06) (xy 349.25 226.06)
		)
		(stroke
			(width 0)
			(type default)
		)
	)
	(wire
		(pts
			(xy 214.63 187.96) (xy 214.63 190.5)
		)
		(stroke
			(width 0)
			(type default)
		)
	)
	(wire
		(pts
			(xy 377.19 52.07) (xy 377.19 58.42)
		)
		(stroke
			(width 0)
			(type default)
		)
	)
	(wire
		(pts
			(xy 318.77 110.49) (xy 318.77 105.41)
		)
		(stroke
			(width 0)
			(type default)
		)
	)
	(wire
		(pts
			(xy 80.01 44.45) (xy 78.74 44.45)
		)
		(stroke
			(width 0)
			(type default)
		)
	)
	(wire
		(pts
			(xy 306.07 161.29) (xy 308.61 161.29)
		)
		(stroke
			(width 0)
			(type default)
		)
	)
	(wire
		(pts
			(xy 359.41 238.76) (xy 359.41 245.11)
		)
		(stroke
			(width 0)
			(type default)
		)
	)
	(wire
		(pts
			(xy 100.33 36.83) (xy 91.44 36.83)
		)
		(stroke
			(width 0)
			(type default)
		)
	)
	(wire
		(pts
			(xy 229.87 228.6) (xy 229.87 232.41)
		)
		(stroke
			(width 0)
			(type default)
		)
	)
	(wire
		(pts
			(xy 332.74 236.22) (xy 345.44 236.22)
		)
		(stroke
			(width 0)
			(type default)
		)
	)
	(wire
		(pts
			(xy 367.03 39.37) (xy 377.19 39.37)
		)
		(stroke
			(width 0)
			(type default)
		)
	)
	(wire
		(pts
			(xy 309.88 44.45) (xy 312.42 44.45)
		)
		(stroke
			(width 0)
			(type default)
		)
	)
	(wire
		(pts
			(xy 297.18 231.14) (xy 300.99 231.14)
		)
		(stroke
			(width 0)
			(type default)
		)
	)
	(wire
		(pts
			(xy 359.41 167.64) (xy 359.41 175.26)
		)
		(stroke
			(width 0)
			(type default)
		)
	)
	(wire
		(pts
			(xy 29.21 184.15) (xy 29.21 185.42)
		)
		(stroke
			(width 0)
			(type default)
		)
	)
	(wire
		(pts
			(xy 133.35 271.78) (xy 133.35 250.19)
		)
		(stroke
			(width 0)
			(type default)
		)
	)
	(wire
		(pts
			(xy 165.1 271.78) (xy 167.64 271.78)
		)
		(stroke
			(width 0)
			(type default)
		)
	)
	(wire
		(pts
			(xy 359.41 190.5) (xy 359.41 191.77)
		)
		(stroke
			(width 0)
			(type default)
		)
	)
	(wire
		(pts
			(xy 355.6 39.37) (xy 367.03 39.37)
		)
		(stroke
			(width 0)
			(type default)
		)
	)
	(wire
		(pts
			(xy 73.66 77.47) (xy 73.66 80.01)
		)
		(stroke
			(width 0)
			(type default)
		)
	)
	(wire
		(pts
			(xy 189.23 271.78) (xy 182.88 271.78)
		)
		(stroke
			(width 0)
			(type default)
		)
	)
	(wire
		(pts
			(xy 71.12 207.01) (xy 71.12 205.74)
		)
		(stroke
			(width 0)
			(type default)
		)
	)
	(wire
		(pts
			(xy 38.1 77.47) (xy 38.1 83.82)
		)
		(stroke
			(width 0)
			(type default)
		)
	)
	(wire
		(pts
			(xy 336.55 90.17) (xy 336.55 91.44)
		)
		(stroke
			(width 0)
			(type default)
		)
	)
	(wire
		(pts
			(xy 306.07 196.85) (xy 308.61 196.85)
		)
		(stroke
			(width 0)
			(type default)
		)
	)
	(wire
		(pts
			(xy 62.23 156.21) (xy 62.23 148.59)
		)
		(stroke
			(width 0)
			(type default)
		)
	)
	(wire
		(pts
			(xy 388.62 52.07) (xy 388.62 58.42)
		)
		(stroke
			(width 0)
			(type default)
		)
	)
	(wire
		(pts
			(xy 287.02 116.84) (xy 287.02 115.57)
		)
		(stroke
			(width 0)
			(type default)
		)
	)
	(wire
		(pts
			(xy 359.41 154.94) (xy 359.41 156.21)
		)
		(stroke
			(width 0)
			(type default)
		)
	)
	(wire
		(pts
			(xy 218.44 232.41) (xy 218.44 241.3)
		)
		(stroke
			(width 0)
			(type default)
		)
	)
	(wire
		(pts
			(xy 336.55 72.39) (xy 355.6 72.39)
		)
		(stroke
			(width 0)
			(type default)
		)
	)
	(wire
		(pts
			(xy 46.99 85.09) (xy 46.99 88.9)
		)
		(stroke
			(width 0)
			(type default)
		)
	)
	(wire
		(pts
			(xy 73.66 273.05) (xy 86.36 273.05)
		)
		(stroke
			(width 0)
			(type default)
		)
	)
	(wire
		(pts
			(xy 71.12 186.69) (xy 71.12 195.58)
		)
		(stroke
			(width 0)
			(type default)
		)
	)
	(wire
		(pts
			(xy 336.55 72.39) (xy 336.55 74.93)
		)
		(stroke
			(width 0)
			(type default)
		)
	)
	(wire
		(pts
			(xy 86.36 146.05) (xy 88.9 146.05)
		)
		(stroke
			(width 0)
			(type default)
		)
	)
	(wire
		(pts
			(xy 259.08 104.14) (xy 259.08 105.41)
		)
		(stroke
			(width 0)
			(type default)
		)
	)
	(wire
		(pts
			(xy 86.36 270.51) (xy 85.09 270.51)
		)
		(stroke
			(width 0)
			(type default)
		)
	)
	(wire
		(pts
			(xy 218.44 232.41) (xy 229.87 232.41)
		)
		(stroke
			(width 0)
			(type default)
		)
	)
	(wire
		(pts
			(xy 308.61 231.14) (xy 308.61 236.22)
		)
		(stroke
			(width 0)
			(type default)
		)
	)
	(wire
		(pts
			(xy 71.12 185.42) (xy 71.12 186.69)
		)
		(stroke
			(width 0)
			(type default)
		)
	)
	(polyline
		(pts
			(xy 254 137.16) (xy 407.67 137.16)
		)
		(stroke
			(width 0)
			(type default)
		)
	)
	(wire
		(pts
			(xy 400.05 105.41) (xy 403.86 105.41)
		)
		(stroke
			(width 0)
			(type default)
		)
	)
	(wire
		(pts
			(xy 247.65 193.04) (xy 247.65 194.31)
		)
		(stroke
			(width 0)
			(type default)
		)
	)
	(wire
		(pts
			(xy 377.19 105.41) (xy 377.19 113.03)
		)
		(stroke
			(width 0)
			(type default)
		)
	)
	(wire
		(pts
			(xy 25.4 77.47) (xy 29.21 77.47)
		)
		(stroke
			(width 0)
			(type default)
		)
	)
	(wire
		(pts
			(xy 308.61 166.37) (xy 311.15 166.37)
		)
		(stroke
			(width 0)
			(type default)
		)
	)
	(wire
		(pts
			(xy 60.96 186.69) (xy 71.12 186.69)
		)
		(stroke
			(width 0)
			(type default)
		)
	)
	(wire
		(pts
			(xy 53.34 146.05) (xy 55.88 146.05)
		)
		(stroke
			(width 0)
			(type default)
		)
	)
	(wire
		(pts
			(xy 73.66 87.63) (xy 73.66 86.36)
		)
		(stroke
			(width 0)
			(type default)
		)
	)
	(wire
		(pts
			(xy 308.61 231.14) (xy 317.5 231.14)
		)
		(stroke
			(width 0)
			(type default)
		)
	)
	(wire
		(pts
			(xy 388.62 72.39) (xy 388.62 80.01)
		)
		(stroke
			(width 0)
			(type default)
		)
	)
	(wire
		(pts
			(xy 53.34 140.97) (xy 63.5 140.97)
		)
		(stroke
			(width 0)
			(type default)
		)
	)
	(wire
		(pts
			(xy 99.06 135.89) (xy 109.22 135.89)
		)
		(stroke
			(width 0)
			(type default)
		)
	)
	(wire
		(pts
			(xy 377.19 72.39) (xy 377.19 80.01)
		)
		(stroke
			(width 0)
			(type default)
		)
	)
	(wire
		(pts
			(xy 337.82 156.21) (xy 345.44 156.21)
		)
		(stroke
			(width 0)
			(type default)
		)
	)
	(wire
		(pts
			(xy 176.53 233.68) (xy 189.23 233.68)
		)
		(stroke
			(width 0)
			(type default)
		)
	)
	(wire
		(pts
			(xy 388.62 85.09) (xy 388.62 91.44)
		)
		(stroke
			(width 0)
			(type default)
		)
	)
	(wire
		(pts
			(xy 91.44 54.61) (xy 101.6 54.61)
		)
		(stroke
			(width 0)
			(type default)
		)
	)
	(wire
		(pts
			(xy 91.44 60.96) (xy 91.44 62.23)
		)
		(stroke
			(width 0)
			(type default)
		)
	)
	(wire
		(pts
			(xy 130.81 271.78) (xy 133.35 271.78)
		)
		(stroke
			(width 0)
			(type default)
		)
	)
	(wire
		(pts
			(xy 73.66 85.09) (xy 73.66 86.36)
		)
		(stroke
			(width 0)
			(type default)
		)
	)
	(polyline
		(pts
			(xy 187.96 201.93) (xy 187.96 170.18)
		)
		(stroke
			(width 0)
			(type default)
		)
	)
	(wire
		(pts
			(xy 199.39 232.41) (xy 201.93 232.41)
		)
		(stroke
			(width 0)
			(type default)
		)
	)
	(wire
		(pts
			(xy 269.24 105.41) (xy 269.24 109.22)
		)
		(stroke
			(width 0)
			(type default)
		)
	)
	(wire
		(pts
			(xy 308.61 110.49) (xy 311.15 110.49)
		)
		(stroke
			(width 0)
			(type default)
		)
	)
	(wire
		(pts
			(xy 29.21 205.74) (xy 29.21 204.47)
		)
		(stroke
			(width 0)
			(type default)
		)
	)
	(wire
		(pts
			(xy 309.88 49.53) (xy 337.82 49.53)
		)
		(stroke
			(width 0)
			(type default)
		)
	)
	(wire
		(pts
			(xy 345.44 166.37) (xy 345.44 168.91)
		)
		(stroke
			(width 0)
			(type default)
		)
	)
	(wire
		(pts
			(xy 182.88 274.32) (xy 189.23 274.32)
		)
		(stroke
			(width 0)
			(type default)
		)
	)
	(wire
		(pts
			(xy 345.44 156.21) (xy 345.44 158.75)
		)
		(stroke
			(width 0)
			(type default)
		)
	)
	(wire
		(pts
			(xy 60.96 186.69) (xy 60.96 194.31)
		)
		(stroke
			(width 0)
			(type default)
		)
	)
	(wire
		(pts
			(xy 337.82 226.06) (xy 345.44 226.06)
		)
		(stroke
			(width 0)
			(type default)
		)
	)
	(wire
		(pts
			(xy 316.23 110.49) (xy 318.77 110.49)
		)
		(stroke
			(width 0)
			(type default)
		)
	)
	(wire
		(pts
			(xy 195.58 193.04) (xy 195.58 194.31)
		)
		(stroke
			(width 0)
			(type default)
		)
	)
	(wire
		(pts
			(xy 297.18 231.14) (xy 297.18 233.68)
		)
		(stroke
			(width 0)
			(type default)
		)
	)
	(wire
		(pts
			(xy 96.52 271.78) (xy 99.06 271.78)
		)
		(stroke
			(width 0)
			(type default)
		)
	)
	(wire
		(pts
			(xy 46.99 88.9) (xy 55.88 88.9)
		)
		(stroke
			(width 0)
			(type default)
		)
	)
	(wire
		(pts
			(xy 53.34 146.05) (xy 53.34 149.86)
		)
		(stroke
			(width 0)
			(type default)
		)
	)
	(wire
		(pts
			(xy 77.47 228.6) (xy 77.47 231.14)
		)
		(stroke
			(width 0)
			(type default)
		)
	)
	(wire
		(pts
			(xy 354.33 226.06) (xy 359.41 226.06)
		)
		(stroke
			(width 0)
			(type default)
		)
	)
	(wire
		(pts
			(xy 100.33 26.67) (xy 113.03 26.67)
		)
		(stroke
			(width 0)
			(type default)
		)
	)
	(wire
		(pts
			(xy 62.23 148.59) (xy 63.5 148.59)
		)
		(stroke
			(width 0)
			(type default)
		)
	)
	(wire
		(pts
			(xy 259.08 71.12) (xy 259.08 72.39)
		)
		(stroke
			(width 0)
			(type default)
		)
	)
	(wire
		(pts
			(xy 336.55 82.55) (xy 336.55 85.09)
		)
		(stroke
			(width 0)
			(type default)
		)
	)
	(wire
		(pts
			(xy 337.82 231.14) (xy 337.82 226.06)
		)
		(stroke
			(width 0)
			(type default)
		)
	)
	(wire
		(pts
			(xy 101.6 190.5) (xy 101.6 195.58)
		)
		(stroke
			(width 0)
			(type default)
		)
	)
	(wire
		(pts
			(xy 218.44 259.08) (xy 218.44 267.97)
		)
		(stroke
			(width 0)
			(type default)
		)
	)
	(wire
		(pts
			(xy 336.55 80.01) (xy 336.55 82.55)
		)
		(stroke
			(width 0)
			(type default)
		)
	)
	(wire
		(pts
			(xy 388.62 39.37) (xy 388.62 46.99)
		)
		(stroke
			(width 0)
			(type default)
		)
	)
	(wire
		(pts
			(xy 240.03 187.96) (xy 240.03 190.5)
		)
		(stroke
			(width 0)
			(type default)
		)
	)
	(wire
		(pts
			(xy 27.94 135.89) (xy 27.94 129.54)
		)
		(stroke
			(width 0)
			(type default)
		)
	)
	(wire
		(pts
			(xy 297.18 168.91) (xy 297.18 170.18)
		)
		(stroke
			(width 0)
			(type default)
		)
	)
	(wire
		(pts
			(xy 397.51 72.39) (xy 402.59 72.39)
		)
		(stroke
			(width 0)
			(type default)
		)
	)
	(wire
		(pts
			(xy 345.44 209.55) (xy 345.44 210.82)
		)
		(stroke
			(width 0)
			(type default)
		)
	)
	(wire
		(pts
			(xy 167.64 250.19) (xy 133.35 250.19)
		)
		(stroke
			(width 0)
			(type default)
		)
	)
	(wire
		(pts
			(xy 285.75 44.45) (xy 289.56 44.45)
		)
		(stroke
			(width 0)
			(type default)
		)
	)
	(wire
		(pts
			(xy 106.68 83.82) (xy 104.14 83.82)
		)
		(stroke
			(width 0)
			(type default)
		)
	)
	(wire
		(pts
			(xy 38.1 77.47) (xy 46.99 77.47)
		)
		(stroke
			(width 0)
			(type default)
		)
	)
	(wire
		(pts
			(xy 345.44 191.77) (xy 345.44 194.31)
		)
		(stroke
			(width 0)
			(type default)
		)
	)
	(wire
		(pts
			(xy 201.93 250.19) (xy 218.44 250.19)
		)
		(stroke
			(width 0)
			(type default)
		)
	)
	(wire
		(pts
			(xy 83.82 133.35) (xy 109.22 133.35)
		)
		(stroke
			(width 0)
			(type default)
		)
	)
	(wire
		(pts
			(xy 167.64 250.19) (xy 201.93 250.19)
		)
		(stroke
			(width 0)
			(type default)
		)
	)
	(wire
		(pts
			(xy 83.82 135.89) (xy 99.06 135.89)
		)
		(stroke
			(width 0)
			(type default)
		)
	)
	(wire
		(pts
			(xy 48.26 133.35) (xy 63.5 133.35)
		)
		(stroke
			(width 0)
			(type default)
		)
	)
	(wire
		(pts
			(xy 330.2 105.41) (xy 336.55 105.41)
		)
		(stroke
			(width 0)
			(type default)
		)
	)
	(wire
		(pts
			(xy 113.03 26.67) (xy 113.03 77.47)
		)
		(stroke
			(width 0)
			(type default)
		)
	)
	(polyline
		(pts
			(xy 254 201.93) (xy 187.96 201.93)
		)
		(stroke
			(width 0)
			(type default)
		)
	)
	(wire
		(pts
			(xy 359.41 156.21) (xy 359.41 162.56)
		)
		(stroke
			(width 0)
			(type default)
		)
	)
	(wire
		(pts
			(xy 308.61 82.55) (xy 336.55 82.55)
		)
		(stroke
			(width 0)
			(type default)
		)
	)
	(wire
		(pts
			(xy 123.19 77.47) (xy 123.19 74.93)
		)
		(stroke
			(width 0)
			(type default)
		)
	)
	(wire
		(pts
			(xy 345.44 233.68) (xy 345.44 236.22)
		)
		(stroke
			(width 0)
			(type default)
		)
	)
	(wire
		(pts
			(xy 365.76 105.41) (xy 365.76 113.03)
		)
		(stroke
			(width 0)
			(type default)
		)
	)
	(wire
		(pts
			(xy 60.96 205.74) (xy 71.12 205.74)
		)
		(stroke
			(width 0)
			(type default)
		)
	)
	(wire
		(pts
			(xy 377.19 39.37) (xy 388.62 39.37)
		)
		(stroke
			(width 0)
			(type default)
		)
	)
	(wire
		(pts
			(xy 359.41 204.47) (xy 359.41 210.82)
		)
		(stroke
			(width 0)
			(type default)
		)
	)
	(wire
		(pts
			(xy 388.62 39.37) (xy 393.7 39.37)
		)
		(stroke
			(width 0)
			(type default)
		)
	)
	(wire
		(pts
			(xy 99.06 44.45) (xy 97.79 44.45)
		)
		(stroke
			(width 0)
			(type default)
		)
	)
	(wire
		(pts
			(xy 60.96 146.05) (xy 63.5 146.05)
		)
		(stroke
			(width 0)
			(type default)
		)
	)
	(wire
		(pts
			(xy 355.6 105.41) (xy 355.6 113.03)
		)
		(stroke
			(width 0)
			(type default)
		)
	)
	(wire
		(pts
			(xy 165.1 232.41) (xy 167.64 232.41)
		)
		(stroke
			(width 0)
			(type default)
		)
	)
	(wire
		(pts
			(xy 367.03 39.37) (xy 367.03 46.99)
		)
		(stroke
			(width 0)
			(type default)
		)
	)
	(wire
		(pts
			(xy 269.24 105.41) (xy 288.29 105.41)
		)
		(stroke
			(width 0)
			(type default)
		)
	)
	(wire
		(pts
			(xy 259.08 72.39) (xy 261.62 72.39)
		)
		(stroke
			(width 0)
			(type default)
		)
	)
	(wire
		(pts
			(xy 142.24 233.68) (xy 154.94 233.68)
		)
		(stroke
			(width 0)
			(type default)
		)
	)
	(wire
		(pts
			(xy 308.61 201.93) (xy 311.15 201.93)
		)
		(stroke
			(width 0)
			(type default)
		)
	)
	(wire
		(pts
			(xy 297.18 204.47) (xy 297.18 205.74)
		)
		(stroke
			(width 0)
			(type default)
		)
	)
	(wire
		(pts
			(xy 86.36 36.83) (xy 86.36 38.1)
		)
		(stroke
			(width 0)
			(type default)
		)
	)
	(wire
		(pts
			(xy 377.19 72.39) (xy 388.62 72.39)
		)
		(stroke
			(width 0)
			(type default)
		)
	)
	(wire
		(pts
			(xy 73.66 77.47) (xy 86.36 77.47)
		)
		(stroke
			(width 0)
			(type default)
		)
	)
	(wire
		(pts
			(xy 241.3 259.08) (xy 241.3 267.97)
		)
		(stroke
			(width 0)
			(type default)
		)
	)
	(wire
		(pts
			(xy 133.35 250.19) (xy 133.35 232.41)
		)
		(stroke
			(width 0)
			(type default)
		)
	)
	(wire
		(pts
			(xy 19.05 185.42) (xy 19.05 193.04)
		)
		(stroke
			(width 0)
			(type default)
		)
	)
	(wire
		(pts
			(xy 337.82 49.53) (xy 337.82 52.07)
		)
		(stroke
			(width 0)
			(type default)
		)
	)
	(wire
		(pts
			(xy 308.61 196.85) (xy 317.5 196.85)
		)
		(stroke
			(width 0)
			(type default)
		)
	)
	(wire
		(pts
			(xy 59.69 26.67) (xy 77.47 26.67)
		)
		(stroke
			(width 0)
			(type default)
		)
	)
	(wire
		(pts
			(xy 308.61 105.41) (xy 318.77 105.41)
		)
		(stroke
			(width 0)
			(type default)
		)
	)
	(wire
		(pts
			(xy 318.77 105.41) (xy 325.12 105.41)
		)
		(stroke
			(width 0)
			(type default)
		)
	)
	(wire
		(pts
			(xy 287.02 83.82) (xy 287.02 82.55)
		)
		(stroke
			(width 0)
			(type default)
		)
	)
	(wire
		(pts
			(xy 40.64 135.89) (xy 63.5 135.89)
		)
		(stroke
			(width 0)
			(type default)
		)
	)
	(wire
		(pts
			(xy 403.86 104.14) (xy 403.86 105.41)
		)
		(stroke
			(width 0)
			(type default)
		)
	)
	(wire
		(pts
			(xy 99.06 135.89) (xy 99.06 137.16)
		)
		(stroke
			(width 0)
			(type default)
		)
	)
	(wire
		(pts
			(xy 201.93 250.19) (xy 201.93 232.41)
		)
		(stroke
			(width 0)
			(type default)
		)
	)
	(wire
		(pts
			(xy 336.55 105.41) (xy 336.55 107.95)
		)
		(stroke
			(width 0)
			(type default)
		)
	)
	(wire
		(pts
			(xy 345.44 173.99) (xy 345.44 175.26)
		)
		(stroke
			(width 0)
			(type default)
		)
	)
	(wire
		(pts
			(xy 269.24 72.39) (xy 269.24 76.2)
		)
		(stroke
			(width 0)
			(type default)
		)
	)
	(wire
		(pts
			(xy 133.35 250.19) (xy 99.06 250.19)
		)
		(stroke
			(width 0)
			(type default)
		)
	)
	(wire
		(pts
			(xy 99.06 142.24) (xy 99.06 143.51)
		)
		(stroke
			(width 0)
			(type default)
		)
	)
	(wire
		(pts
			(xy 91.44 35.56) (xy 101.6 35.56)
		)
		(stroke
			(width 0)
			(type default)
		)
	)
	(wire
		(pts
			(xy 130.81 232.41) (xy 133.35 232.41)
		)
		(stroke
			(width 0)
			(type default)
		)
	)
	(wire
		(pts
			(xy 86.36 60.96) (xy 86.36 62.23)
		)
		(stroke
			(width 0)
			(type default)
		)
	)
	(wire
		(pts
			(xy 359.41 226.06) (xy 359.41 233.68)
		)
		(stroke
			(width 0)
			(type default)
		)
	)
	(wire
		(pts
			(xy 38.1 88.9) (xy 38.1 93.98)
		)
		(stroke
			(width 0)
			(type default)
		)
	)
	(wire
		(pts
			(xy 308.61 196.85) (xy 308.61 201.93)
		)
		(stroke
			(width 0)
			(type default)
		)
	)
	(wire
		(pts
			(xy 95.25 26.67) (xy 100.33 26.67)
		)
		(stroke
			(width 0)
			(type default)
		)
	)
	(wire
		(pts
			(xy 336.55 115.57) (xy 336.55 118.11)
		)
		(stroke
			(width 0)
			(type default)
		)
	)
	(wire
		(pts
			(xy 308.61 72.39) (xy 318.77 72.39)
		)
		(stroke
			(width 0)
			(type default)
		)
	)
	(wire
		(pts
			(xy 80.01 81.28) (xy 86.36 81.28)
		)
		(stroke
			(width 0)
			(type default)
		)
	)
	(wire
		(pts
			(xy 287.02 82.55) (xy 288.29 82.55)
		)
		(stroke
			(width 0)
			(type default)
		)
	)
	(wire
		(pts
			(xy 109.22 133.35) (xy 109.22 135.89)
		)
		(stroke
			(width 0)
			(type default)
		)
	)
	(wire
		(pts
			(xy 99.06 271.78) (xy 99.06 250.19)
		)
		(stroke
			(width 0)
			(type default)
		)
	)
	(wire
		(pts
			(xy 83.82 146.05) (xy 86.36 146.05)
		)
		(stroke
			(width 0)
			(type default)
		)
	)
	(wire
		(pts
			(xy 104.14 77.47) (xy 113.03 77.47)
		)
		(stroke
			(width 0)
			(type default)
		)
	)
	(wire
		(pts
			(xy 46.99 88.9) (xy 46.99 90.17)
		)
		(stroke
			(width 0)
			(type default)
		)
	)
	(wire
		(pts
			(xy 40.64 129.54) (xy 40.64 133.35)
		)
		(stroke
			(width 0)
			(type default)
		)
	)
	(wire
		(pts
			(xy 96.52 232.41) (xy 99.06 232.41)
		)
		(stroke
			(width 0)
			(type default)
		)
	)
	(wire
		(pts
			(xy 337.82 46.99) (xy 337.82 49.53)
		)
		(stroke
			(width 0)
			(type default)
		)
	)
	(wire
		(pts
			(xy 355.6 118.11) (xy 355.6 124.46)
		)
		(stroke
			(width 0)
			(type default)
		)
	)
	(wire
		(pts
			(xy 388.62 72.39) (xy 392.43 72.39)
		)
		(stroke
			(width 0)
			(type default)
		)
	)
	(wire
		(pts
			(xy 337.82 196.85) (xy 337.82 191.77)
		)
		(stroke
			(width 0)
			(type default)
		)
	)
	(wire
		(pts
			(xy 104.14 81.28) (xy 113.03 81.28)
		)
		(stroke
			(width 0)
			(type default)
		)
	)
	(wire
		(pts
			(xy 297.18 196.85) (xy 300.99 196.85)
		)
		(stroke
			(width 0)
			(type default)
		)
	)
	(wire
		(pts
			(xy 77.47 26.67) (xy 77.47 36.83)
		)
		(stroke
			(width 0)
			(type default)
		)
	)
	(wire
		(pts
			(xy 60.96 199.39) (xy 60.96 205.74)
		)
		(stroke
			(width 0)
			(type default)
		)
	)
	(wire
		(pts
			(xy 297.18 161.29) (xy 297.18 163.83)
		)
		(stroke
			(width 0)
			(type default)
		)
	)
	(wire
		(pts
			(xy 208.28 187.96) (xy 208.28 190.5)
		)
		(stroke
			(width 0)
			(type default)
		)
	)
	(wire
		(pts
			(xy 182.88 267.97) (xy 182.88 271.78)
		)
		(stroke
			(width 0)
			(type default)
		)
	)
	(wire
		(pts
			(xy 336.55 123.19) (xy 336.55 124.46)
		)
		(stroke
			(width 0)
			(type default)
		)
	)
	(wire
		(pts
			(xy 109.22 142.24) (xy 109.22 143.51)
		)
		(stroke
			(width 0)
			(type default)
		)
	)
	(wire
		(pts
			(xy 78.74 52.07) (xy 86.36 52.07)
		)
		(stroke
			(width 0)
			(type default)
		)
	)
	(wire
		(pts
			(xy 297.18 229.87) (xy 297.18 231.14)
		)
		(stroke
			(width 0)
			(type default)
		)
	)
	(wire
		(pts
			(xy 345.44 156.21) (xy 349.25 156.21)
		)
		(stroke
			(width 0)
			(type default)
		)
	)
	(wire
		(pts
			(xy 377.19 105.41) (xy 388.62 105.41)
		)
		(stroke
			(width 0)
			(type default)
		)
	)
	(wire
		(pts
			(xy 36.83 135.89) (xy 40.64 135.89)
		)
		(stroke
			(width 0)
			(type default)
		)
	)
	(wire
		(pts
			(xy 402.59 72.39) (xy 402.59 71.12)
		)
		(stroke
			(width 0)
			(type default)
		)
	)
	(wire
		(pts
			(xy 34.29 77.47) (xy 38.1 77.47)
		)
		(stroke
			(width 0)
			(type default)
		)
	)
	(wire
		(pts
			(xy 345.44 199.39) (xy 345.44 201.93)
		)
		(stroke
			(width 0)
			(type default)
		)
	)
	(wire
		(pts
			(xy 388.62 118.11) (xy 388.62 124.46)
		)
		(stroke
			(width 0)
			(type default)
		)
	)
	(wire
		(pts
			(xy 153.67 270.51) (xy 154.94 270.51)
		)
		(stroke
			(width 0)
			(type default)
		)
	)
	(wire
		(pts
			(xy 330.2 39.37) (xy 337.82 39.37)
		)
		(stroke
			(width 0)
			(type default)
		)
	)
	(wire
		(pts
			(xy 355.6 85.09) (xy 355.6 91.44)
		)
		(stroke
			(width 0)
			(type default)
		)
	)
	(wire
		(pts
			(xy 297.18 238.76) (xy 297.18 240.03)
		)
		(stroke
			(width 0)
			(type default)
		)
	)
	(wire
		(pts
			(xy 91.44 34.29) (xy 91.44 35.56)
		)
		(stroke
			(width 0)
			(type default)
		)
	)
	(wire
		(pts
			(xy 59.69 96.52) (xy 59.69 97.79)
		)
		(stroke
			(width 0)
			(type default)
		)
	)
	(wire
		(pts
			(xy 330.2 72.39) (xy 336.55 72.39)
		)
		(stroke
			(width 0)
			(type default)
		)
	)
	(wire
		(pts
			(xy 320.04 44.45) (xy 320.04 39.37)
		)
		(stroke
			(width 0)
			(type default)
		)
	)
	(wire
		(pts
			(xy 308.61 115.57) (xy 336.55 115.57)
		)
		(stroke
			(width 0)
			(type default)
		)
	)
	(wire
		(pts
			(xy 86.36 52.07) (xy 86.36 55.88)
		)
		(stroke
			(width 0)
			(type default)
		)
	)
	(wire
		(pts
			(xy 308.61 161.29) (xy 308.61 166.37)
		)
		(stroke
			(width 0)
			(type default)
		)
	)
	(wire
		(pts
			(xy 91.44 36.83) (xy 91.44 38.1)
		)
		(stroke
			(width 0)
			(type default)
		)
	)
	(wire
		(pts
			(xy 99.06 52.07) (xy 99.06 44.45)
		)
		(stroke
			(width 0)
			(type default)
		)
	)
	(wire
		(pts
			(xy 86.36 52.07) (xy 99.06 52.07)
		)
		(stroke
			(width 0)
			(type default)
		)
	)
	(wire
		(pts
			(xy 284.48 110.49) (xy 288.29 110.49)
		)
		(stroke
			(width 0)
			(type default)
		)
	)
	(wire
		(pts
			(xy 31.75 135.89) (xy 27.94 135.89)
		)
		(stroke
			(width 0)
			(type default)
		)
	)
	(wire
		(pts
			(xy 365.76 118.11) (xy 365.76 124.46)
		)
		(stroke
			(width 0)
			(type default)
		)
	)
	(wire
		(pts
			(xy 354.33 156.21) (xy 359.41 156.21)
		)
		(stroke
			(width 0)
			(type default)
		)
	)
	(wire
		(pts
			(xy 337.82 57.15) (xy 337.82 58.42)
		)
		(stroke
			(width 0)
			(type default)
		)
	)
	(wire
		(pts
			(xy 297.18 160.02) (xy 297.18 161.29)
		)
		(stroke
			(width 0)
			(type default)
		)
	)
	(wire
		(pts
			(xy 77.47 26.67) (xy 82.55 26.67)
		)
		(stroke
			(width 0)
			(type default)
		)
	)
	(wire
		(pts
			(xy 36.83 129.54) (xy 40.64 129.54)
		)
		(stroke
			(width 0)
			(type default)
		)
	)
	(wire
		(pts
			(xy 355.6 52.07) (xy 355.6 58.42)
		)
		(stroke
			(width 0)
			(type default)
		)
	)
	(wire
		(pts
			(xy 260.35 38.1) (xy 260.35 39.37)
		)
		(stroke
			(width 0)
			(type default)
		)
	)
	(wire
		(pts
			(xy 48.26 142.24) (xy 48.26 143.51)
		)
		(stroke
			(width 0)
			(type default)
		)
	)
	(wire
		(pts
			(xy 288.29 49.53) (xy 289.56 49.53)
		)
		(stroke
			(width 0)
			(type default)
		)
	)
	(wire
		(pts
			(xy 106.68 83.82) (xy 106.68 88.9)
		)
		(stroke
			(width 0)
			(type default)
		)
	)
	(wire
		(pts
			(xy 365.76 105.41) (xy 377.19 105.41)
		)
		(stroke
			(width 0)
			(type default)
		)
	)
	(wire
		(pts
			(xy 266.7 72.39) (xy 269.24 72.39)
		)
		(stroke
			(width 0)
			(type default)
		)
	)
	(wire
		(pts
			(xy 46.99 77.47) (xy 46.99 80.01)
		)
		(stroke
			(width 0)
			(type default)
		)
	)
	(wire
		(pts
			(xy 367.03 52.07) (xy 367.03 58.42)
		)
		(stroke
			(width 0)
			(type default)
		)
	)
	(wire
		(pts
			(xy 297.18 195.58) (xy 297.18 196.85)
		)
		(stroke
			(width 0)
			(type default)
		)
	)
	(wire
		(pts
			(xy 297.18 161.29) (xy 300.99 161.29)
		)
		(stroke
			(width 0)
			(type default)
		)
	)
	(wire
		(pts
			(xy 146.05 228.6) (xy 146.05 231.14)
		)
		(stroke
			(width 0)
			(type default)
		)
	)
	(wire
		(pts
			(xy 113.03 77.47) (xy 115.57 77.47)
		)
		(stroke
			(width 0)
			(type default)
		)
	)
	(wire
		(pts
			(xy 359.41 224.79) (xy 359.41 226.06)
		)
		(stroke
			(width 0)
			(type default)
		)
	)
	(polyline
		(pts
			(xy 12.7 110.49) (xy 130.81 110.49)
		)
		(stroke
			(width 0)
			(type default)
		)
	)
	(wire
		(pts
			(xy 27.94 129.54) (xy 27.94 127)
		)
		(stroke
			(width 0)
			(type default)
		)
	)
	(wire
		(pts
			(xy 241.3 246.38) (xy 241.3 254)
		)
		(stroke
			(width 0)
			(type default)
		)
	)
	(wire
		(pts
			(xy 355.6 105.41) (xy 365.76 105.41)
		)
		(stroke
			(width 0)
			(type default)
		)
	)
	(wire
		(pts
			(xy 59.69 26.67) (xy 59.69 96.52)
		)
		(stroke
			(width 0)
			(type default)
		)
	)
	(wire
		(pts
			(xy 388.62 105.41) (xy 388.62 113.03)
		)
		(stroke
			(width 0)
			(type default)
		)
	)
	(wire
		(pts
			(xy 270.51 39.37) (xy 289.56 39.37)
		)
		(stroke
			(width 0)
			(type default)
		)
	)
	(wire
		(pts
			(xy 78.74 44.45) (xy 78.74 52.07)
		)
		(stroke
			(width 0)
			(type default)
		)
	)
	(wire
		(pts
			(xy 318.77 72.39) (xy 325.12 72.39)
		)
		(stroke
			(width 0)
			(type default)
		)
	)
	(wire
		(pts
			(xy 220.98 187.96) (xy 220.98 190.5)
		)
		(stroke
			(width 0)
			(type default)
		)
	)
	(wire
		(pts
			(xy 29.21 196.85) (xy 29.21 204.47)
		)
		(stroke
			(width 0)
			(type default)
		)
	)
	(wire
		(pts
			(xy 316.23 77.47) (xy 318.77 77.47)
		)
		(stroke
			(width 0)
			(type default)
		)
	)
	(wire
		(pts
			(xy 167.64 250.19) (xy 167.64 232.41)
		)
		(stroke
			(width 0)
			(type default)
		)
	)
	(wire
		(pts
			(xy 101.6 35.56) (xy 101.6 54.61)
		)
		(stroke
			(width 0)
			(type default)
		)
	)
	(wire
		(pts
			(xy 27.94 129.54) (xy 31.75 129.54)
		)
		(stroke
			(width 0)
			(type default)
		)
	)
	(wire
		(pts
			(xy 83.82 83.82) (xy 86.36 83.82)
		)
		(stroke
			(width 0)
			(type default)
		)
	)
	(wire
		(pts
			(xy 229.87 232.41) (xy 241.3 232.41)
		)
		(stroke
			(width 0)
			(type default)
		)
	)
	(wire
		(pts
			(xy 359.41 191.77) (xy 359.41 199.39)
		)
		(stroke
			(width 0)
			(type default)
		)
	)
	(wire
		(pts
			(xy 77.47 36.83) (xy 86.36 36.83)
		)
		(stroke
			(width 0)
			(type default)
		)
	)
	(label "1V5_OUT"
		(at 367.03 105.41 0)
		(effects
			(font
				(size 1.27 1.27)
			)
			(justify left bottom)
		)
	)
	(label "1V0_SW"
		(at 309.245 72.39 0)
		(effects
			(font
				(size 1.27 1.27)
			)
			(justify left bottom)
		)
	)
	(label "VREF_0V45"
		(at 142.24 233.68 0)
		(effects
			(font
				(size 1.27 1.27)
			)
			(justify left bottom)
		)
	)
	(label "5V_1V0_IN"
		(at 275.59 72.39 0)
		(effects
			(font
				(size 1.27 1.27)
			)
			(justify left bottom)
		)
	)
	(label "VREF_0V45"
		(at 107.95 233.68 0)
		(effects
			(font
				(size 1.27 1.27)
			)
			(justify left bottom)
		)
	)
	(label "VREF_0V45"
		(at 143.51 273.05 0)
		(effects
			(font
				(size 1.27 1.27)
			)
			(justify left bottom)
		)
	)
	(label "VREF_0V45"
		(at 73.66 273.05 0)
		(effects
			(font
				(size 1.27 1.27)
			)
			(justify left bottom)
		)
	)
	(label "3V3_OUT"
		(at 368.3 39.37 0)
		(effects
			(font
				(size 1.27 1.27)
			)
			(justify left bottom)
		)
	)
	(label "5V_3V3_IN"
		(at 275.59 39.37 0)
		(effects
			(font
				(size 1.27 1.27)
			)
			(justify left bottom)
		)
	)
	(label "~{FAULT}"
		(at 80.01 81.28 0)
		(effects
			(font
				(size 1.27 1.27)
			)
			(justify left bottom)
		)
	)
	(label "VREF_0V45"
		(at 74.93 233.68 0)
		(effects
			(font
				(size 1.27 1.27)
			)
			(justify left bottom)
		)
	)
	(label "FFC2_5V_1"
		(at 48.26 77.47 0)
		(effects
			(font
				(size 1.27 1.27)
			)
			(justify left bottom)
		)
	)
	(label "VREF_0V45"
		(at 107.95 273.05 0)
		(effects
			(font
				(size 1.27 1.27)
			)
			(justify left bottom)
		)
	)
	(label "VREF_0V45"
		(at 113.03 195.58 180)
		(effects
			(font
				(size 1.27 1.27)
			)
			(justify right bottom)
		)
	)
	(label "5V_1V5_IN"
		(at 276.225 105.41 0)
		(effects
			(font
				(size 1.27 1.27)
			)
			(justify left bottom)
		)
	)
	(label "5V_I"
		(at 106.68 77.47 0)
		(effects
			(font
				(size 1.27 1.27)
			)
			(justify left bottom)
		)
	)
	(label "VREF_0V45"
		(at 176.53 233.68 0)
		(effects
			(font
				(size 1.27 1.27)
			)
			(justify left bottom)
		)
	)
	(label "3V3_SW"
		(at 311.15 39.37 0)
		(effects
			(font
				(size 1.27 1.27)
			)
			(justify left bottom)
		)
	)
	(label "1V0_OUT"
		(at 368.3 72.39 0)
		(effects
			(font
				(size 1.27 1.27)
			)
			(justify left bottom)
		)
	)
	(label "~{FAULT}"
		(at 55.88 88.9 180)
		(effects
			(font
				(size 1.27 1.27)
			)
			(justify right bottom)
		)
	)
	(label "1V5_SW"
		(at 309.88 105.41 0)
		(effects
			(font
				(size 1.27 1.27)
			)
			(justify left bottom)
		)
	)
	(global_label "USB_POWER_IN"
		(shape input)
		(at 39.37 26.67 180)
		(fields_autoplaced yes)
		(effects
			(font
				(size 1.27 1.27)
			)
			(justify right)
		)
		(property "Intersheetrefs" "${INTERSHEET_REFS}"
			(at 22.8055 26.5906 0)
			(effects
				(font
					(size 1.27 1.27)
				)
				(justify right)
				(hide yes)
			)
		)
	)
	(global_label "Vtt"
		(shape input)
		(at 109.22 130.81 90)
		(fields_autoplaced yes)
		(effects
			(font
				(size 1.27 1.27)
			)
			(justify left)
		)
		(property "Intersheetrefs" "${INTERSHEET_REFS}"
			(at 109.1406 125.8569 90)
			(effects
				(font
					(size 1.27 1.27)
				)
				(justify left)
				(hide yes)
			)
		)
	)
	(global_label "1V0_Power"
		(shape input)
		(at 111.76 228.6 90)
		(fields_autoplaced yes)
		(effects
			(font
				(size 1.27 1.27)
			)
			(justify left)
		)
		(property "Intersheetrefs" "${INTERSHEET_REFS}"
			(at 111.6806 216.0874 90)
			(effects
				(font
					(size 1.27 1.27)
				)
				(justify left)
				(hide yes)
			)
		)
	)
	(global_label "1V0_Clean"
		(shape input)
		(at 146.05 228.6 90)
		(fields_autoplaced yes)
		(effects
			(font
				(size 1.27 1.27)
			)
			(justify left)
		)
		(property "Intersheetrefs" "${INTERSHEET_REFS}"
			(at 145.9706 216.3898 90)
			(effects
				(font
					(size 1.27 1.27)
				)
				(justify left)
				(hide yes)
			)
		)
	)
	(global_label "1V0_Clean"
		(shape input)
		(at 359.41 154.94 90)
		(fields_autoplaced yes)
		(effects
			(font
				(size 1.27 1.27)
			)
			(justify left)
		)
		(property "Intersheetrefs" "${INTERSHEET_REFS}"
			(at 359.3306 142.7298 90)
			(effects
				(font
					(size 1.27 1.27)
				)
				(justify left)
				(hide yes)
			)
		)
	)
	(global_label "1V0_Power"
		(shape input)
		(at 214.63 187.96 90)
		(fields_autoplaced yes)
		(effects
			(font
				(size 1.27 1.27)
			)
			(justify left)
		)
		(property "Intersheetrefs" "${INTERSHEET_REFS}"
			(at 214.5506 175.4474 90)
			(effects
				(font
					(size 1.27 1.27)
				)
				(justify left)
				(hide yes)
			)
		)
	)
	(global_label "FFC2_5V"
		(shape input)
		(at 25.4 77.47 180)
		(fields_autoplaced yes)
		(effects
			(font
				(size 1.27 1.27)
			)
			(justify right)
		)
		(property "Intersheetrefs" "${INTERSHEET_REFS}"
			(at 15.0645 77.3906 0)
			(effects
				(font
					(size 1.27 1.27)
				)
				(justify right)
				(hide yes)
			)
		)
	)
	(global_label "Vtt"
		(shape input)
		(at 153.67 267.97 90)
		(fields_autoplaced yes)
		(effects
			(font
				(size 1.27 1.27)
			)
			(justify left)
		)
		(property "Intersheetrefs" "${INTERSHEET_REFS}"
			(at 153.5906 263.0169 90)
			(effects
				(font
					(size 1.27 1.27)
				)
				(justify left)
				(hide yes)
			)
		)
	)
	(global_label "1V0_Clean"
		(shape input)
		(at 220.98 187.96 90)
		(fields_autoplaced yes)
		(effects
			(font
				(size 1.27 1.27)
			)
			(justify left)
		)
		(property "Intersheetrefs" "${INTERSHEET_REFS}"
			(at 220.9006 175.7498 90)
			(effects
				(font
					(size 1.27 1.27)
				)
				(justify left)
				(hide yes)
			)
		)
	)
	(global_label "Vref"
		(shape input)
		(at 88.9 146.05 0)
		(fields_autoplaced yes)
		(effects
			(font
				(size 1.27 1.27)
			)
			(justify left)
		)
		(property "Intersheetrefs" "${INTERSHEET_REFS}"
			(at 95.0021 145.9706 0)
			(effects
				(font
					(size 1.27 1.27)
				)
				(justify left)
				(hide yes)
			)
		)
	)
	(global_label "1V0_Power"
		(shape input)
		(at 402.59 71.12 90)
		(fields_autoplaced yes)
		(effects
			(font
				(size 1.27 1.27)
			)
			(justify left)
		)
		(property "Intersheetrefs" "${INTERSHEET_REFS}"
			(at 402.5106 58.6074 90)
			(effects
				(font
					(size 1.27 1.27)
				)
				(justify left)
				(hide yes)
			)
		)
	)
	(symbol
		(lib_id "antmicropower:+5V")
		(at 201.93 187.96 0)
		(unit 1)
		(exclude_from_sim no)
		(in_bom yes)
		(on_board yes)
		(dnp no)
		(fields_autoplaced yes)
		(property "Reference" "#PWR029"
			(at 217.17 190.5 0)
			(effects
				(font
					(size 1.27 1.27)
					(thickness 0.15)
				)
				(justify left bottom)
				(hide yes)
			)
		)
		(property "Value" "+5V"
			(at 201.93 182.88 0)
			(effects
				(font
					(size 1.27 1.27)
					(thickness 0.15)
				)
			)
		)
		(property "Footprint" ""
			(at 217.17 195.58 0)
			(effects
				(font
					(size 1.27 1.27)
					(thickness 0.15)
				)
				(justify left bottom)
				(hide yes)
			)
		)
		(property "Datasheet" ""
			(at 217.17 198.12 0)
			(effects
				(font
					(size 1.27 1.27)
					(thickness 0.15)
				)
				(justify left bottom)
				(hide yes)
			)
		)
		(property "Description" ""
			(at 201.93 187.96 0)
			(effects
				(font
					(size 1.27 1.27)
				)
				(hide yes)
			)
		)
		(property "Author" "Antmicro"
			(at 217.17 195.58 0)
			(effects
				(font
					(size 1.27 1.27)
					(thickness 0.15)
				)
				(justify left bottom)
				(hide yes)
			)
		)
		(property "License" "Apache-2.0"
			(at 217.17 198.12 0)
			(effects
				(font
					(size 1.27 1.27)
					(thickness 0.15)
				)
				(justify left bottom)
				(hide yes)
			)
		)
		(pin "1"
		)
		(instances
			(project "sdi-mipi-video-converter"
				(path ""
					(reference "#PWR029")
					(unit 1)
				)
			)
		)
	)
	(symbol
		(lib_id "antmicroCapacitors0603:C_10u_0603")
		(at 53.34 154.94 270)
		(mirror x)
		(unit 1)
		(exclude_from_sim no)
		(in_bom yes)
		(on_board yes)
		(dnp no)
		(fields_autoplaced yes)
		(property "Reference" "C108"
			(at 55.88 151.1235 90)
			(effects
				(font
					(size 1.27 1.27)
					(thickness 0.15)
				)
				(justify left)
			)
		)
		(property "Value" "C_10u_0603"
			(at 43.18 134.62 0)
			(effects
				(font
					(size 1.27 1.27)
					(thickness 0.15)
				)
				(justify left bottom)
				(hide yes)
			)
		)
		(property "Footprint" "antmicro-footprints:C_0603_1608Metric"
			(at 40.64 134.62 0)
			(effects
				(font
					(size 1.27 1.27)
					(thickness 0.15)
				)
				(justify left bottom)
				(hide yes)
			)
		)
		(property "Datasheet" "https://www.murata.com/products/productdetail?partno=GRM188R61A106KE69%23"
			(at 38.1 134.62 0)
			(effects
				(font
					(size 1.27 1.27)
					(thickness 0.15)
				)
				(justify left bottom)
				(hide yes)
			)
		)
		(property "Description" "SMD Multilayer Ceramic Capacitor, 10 µF, 10 V, 0603 [1608 Metric], ± 10%, X5R, GRM Series"
			(at 53.34 154.94 0)
			(effects
				(font
					(size 1.27 1.27)
				)
				(hide yes)
			)
		)
		(property "Manufacturer" "Murata"
			(at 33.02 134.62 0)
			(effects
				(font
					(size 1.27 1.27)
					(thickness 0.15)
				)
				(justify left bottom)
				(hide yes)
			)
		)
		(property "MPN" "GRM188R61A106KE69D"
			(at 35.56 134.62 0)
			(effects
				(font
					(size 1.27 1.27)
					(thickness 0.15)
				)
				(justify left bottom)
				(hide yes)
			)
		)
		(property "Val" "10u"
			(at 55.88 153.6635 90)
			(effects
				(font
					(size 1.27 1.27)
					(thickness 0.15)
				)
				(justify left)
			)
		)
		(property "License" "Apache-2.0"
			(at 30.48 134.62 0)
			(effects
				(font
					(size 1.27 1.27)
					(thickness 0.15)
				)
				(justify left bottom)
				(hide yes)
			)
		)
		(property "Author" "Antmicro"
			(at 27.94 134.62 0)
			(effects
				(font
					(size 1.27 1.27)
					(thickness 0.15)
				)
				(justify left bottom)
				(hide yes)
			)
		)
		(property "Voltage" ""
			(at 25.4 134.62 0)
			(effects
				(font
					(size 1.27 1.27)
				)
				(justify left bottom)
				(hide yes)
			)
		)
		(property "Dielectric" "template_dielectric"
			(at 22.86 134.62 0)
			(effects
				(font
					(size 1.27 1.27)
				)
				(justify left bottom)
				(hide yes)
			)
		)
		(pin "1"
		)
		(pin "2"
		)
		(instances
			(project "sdi-mipi-video-converter"
				(path ""
					(reference "C108")
					(unit 1)
				)
			)
		)
	)
	(symbol
		(lib_id "antmicropower:+3.3V")
		(at 297.18 229.87 0)
		(unit 1)
		(exclude_from_sim no)
		(in_bom yes)
		(on_board yes)
		(dnp no)
		(fields_autoplaced yes)
		(property "Reference" "#PWR051"
			(at 297.18 233.68 0)
			(effects
				(font
					(size 1.27 1.27)
				)
				(hide yes)
			)
		)
		(property "Value" "+3V3"
			(at 297.18 224.79 0)
			(effects
				(font
					(size 1.27 1.27)
				)
			)
		)
		(property "Footprint" ""
			(at 297.18 229.87 0)
			(effects
				(font
					(size 1.27 1.27)
				)
				(hide yes)
			)
		)
		(property "Datasheet" ""
			(at 297.18 229.87 0)
			(effects
				(font
					(size 1.27 1.27)
				)
				(hide yes)
			)
		)
		(property "Description" ""
			(at 297.18 229.87 0)
			(effects
				(font
					(size 1.27 1.27)
				)
				(hide yes)
			)
		)
		(pin "1"
		)
		(instances
			(project "sdi-mipi-video-converter"
				(path ""
					(reference "#PWR051")
					(unit 1)
				)
			)
		)
	)
	(symbol
		(lib_id "antmicroResistors0402:R_1k5_0402")
		(at 336.55 118.11 270)
		(unit 1)
		(exclude_from_sim no)
		(in_bom yes)
		(on_board yes)
		(dnp no)
		(fields_autoplaced yes)
		(property "Reference" "R12"
			(at 339.09 119.3799 90)
			(effects
				(font
					(size 1.27 1.27)
					(thickness 0.15)
				)
				(justify left)
			)
		)
		(property "Value" "R_1k5_0402"
			(at 323.85 138.43 0)
			(effects
				(font
					(size 1.27 1.27)
					(thickness 0.15)
				)
				(justify left bottom)
				(hide yes)
			)
		)
		(property "Footprint" "antmicro-footprints:R_0402_1005Metric"
			(at 321.31 138.43 0)
			(effects
				(font
					(size 1.27 1.27)
					(thickness 0.15)
				)
				(justify left bottom)
				(hide yes)
			)
		)
		(property "Datasheet" "https://www.bourns.com/docs/product-datasheets/cr.pdf"
			(at 318.77 138.43 0)
			(effects
				(font
					(size 1.27 1.27)
					(thickness 0.15)
				)
				(justify left bottom)
				(hide yes)
			)
		)
		(property "Description" "SMD Chip Resistor, 1.5 kohm, ± 1%, 62.5 mW, 0402 [1005 Metric], Thick Film, General Purpose"
			(at 336.55 118.11 0)
			(effects
				(font
					(size 1.27 1.27)
				)
				(hide yes)
			)
		)
		(property "Manufacturer" "Bourns"
			(at 313.69 138.43 0)
			(effects
				(font
					(size 1.27 1.27)
					(thickness 0.15)
				)
				(justify left bottom)
				(hide yes)
			)
		)
		(property "MPN" "CR0402-FX-1501GLF"
			(at 316.23 138.43 0)
			(effects
				(font
					(size 1.27 1.27)
					(thickness 0.15)
				)
				(justify left bottom)
				(hide yes)
			)
		)
		(property "Val" "1k5"
			(at 339.09 121.9199 90)
			(effects
				(font
					(size 1.27 1.27)
					(thickness 0.15)
				)
				(justify left)
			)
		)
		(property "License" "Apache-2.0"
			(at 311.15 138.43 0)
			(effects
				(font
					(size 1.27 1.27)
					(thickness 0.15)
				)
				(justify left bottom)
				(hide yes)
			)
		)
		(property "Author" "Antmicro"
			(at 308.61 138.43 0)
			(effects
				(font
					(size 1.27 1.27)
					(thickness 0.15)
				)
				(justify left bottom)
				(hide yes)
			)
		)
		(property "Tolerance" "1%"
			(at 326.39 138.43 0)
			(effects
				(font
					(size 1.27 1.27)
				)
				(justify left bottom)
				(hide yes)
			)
		)
		(pin "1"
		)
		(pin "2"
		)
		(instances
			(project "sdi-mipi-video-converter"
				(path ""
					(reference "R12")
					(unit 1)
				)
			)
		)
	)
	(symbol
		(lib_id "antmicroCapacitors0603:C_22u_0603")
		(at 99.06 142.24 90)
		(unit 1)
		(exclude_from_sim no)
		(in_bom yes)
		(on_board yes)
		(dnp no)
		(fields_autoplaced yes)
		(property "Reference" "C7"
			(at 96.52 138.4235 90)
			(effects
				(font
					(size 1.27 1.27)
					(thickness 0.15)
				)
				(justify left)
			)
		)
		(property "Value" "C_22u_0603"
			(at 109.22 121.92 0)
			(effects
				(font
					(size 1.27 1.27)
					(thickness 0.15)
				)
				(justify left bottom)
				(hide yes)
			)
		)
		(property "Footprint" "antmicro-footprints:C_0603_1608Metric"
			(at 111.76 121.92 0)
			(effects
				(font
					(size 1.27 1.27)
					(thickness 0.15)
				)
				(justify left bottom)
				(hide yes)
			)
		)
		(property "Datasheet" "https://www.murata.com/products/productdetail?partno=GRM188R60J226MEA0%23"
			(at 114.3 121.92 0)
			(effects
				(font
					(size 1.27 1.27)
					(thickness 0.15)
				)
				(justify left bottom)
				(hide yes)
			)
		)
		(property "Description" "SMD Multilayer Ceramic Capacitor, 22 µF, 6.3 V, 0603 [1608 Metric], ± 20%, X5R, GRM Series"
			(at 99.06 142.24 0)
			(effects
				(font
					(size 1.27 1.27)
				)
				(hide yes)
			)
		)
		(property "Manufacturer" "Murata"
			(at 119.38 121.92 0)
			(effects
				(font
					(size 1.27 1.27)
					(thickness 0.15)
				)
				(justify left bottom)
				(hide yes)
			)
		)
		(property "MPN" "GRM188R60J226MEA0D"
			(at 116.84 121.92 0)
			(effects
				(font
					(size 1.27 1.27)
					(thickness 0.15)
				)
				(justify left bottom)
				(hide yes)
			)
		)
		(property "Val" "22u"
			(at 96.52 140.9635 90)
			(effects
				(font
					(size 1.27 1.27)
					(thickness 0.15)
				)
				(justify left)
			)
		)
		(property "License" "Apache-2.0"
			(at 121.92 121.92 0)
			(effects
				(font
					(size 1.27 1.27)
					(thickness 0.15)
				)
				(justify left bottom)
				(hide yes)
			)
		)
		(property "Author" "Antmicro"
			(at 124.46 121.92 0)
			(effects
				(font
					(size 1.27 1.27)
					(thickness 0.15)
				)
				(justify left bottom)
				(hide yes)
			)
		)
		(property "Voltage" ""
			(at 127 121.92 0)
			(effects
				(font
					(size 1.27 1.27)
				)
				(justify left bottom)
				(hide yes)
			)
		)
		(property "Dielectric" ""
			(at 129.54 121.92 0)
			(effects
				(font
					(size 1.27 1.27)
				)
				(justify left bottom)
				(hide yes)
			)
		)
		(pin "1"
		)
		(pin "2"
		)
		(instances
			(project "sdi-mipi-video-converter"
				(path ""
					(reference "C7")
					(unit 1)
				)
			)
		)
	)
	(symbol
		(lib_id "antmicropower:GND")
		(at 297.18 205.74 0)
		(unit 1)
		(exclude_from_sim no)
		(in_bom yes)
		(on_board yes)
		(dnp no)
		(fields_autoplaced yes)
		(property "Reference" "#PWR050"
			(at 306.07 208.28 0)
			(effects
				(font
					(size 1.27 1.27)
					(thickness 0.15)
				)
				(justify left bottom)
				(hide yes)
			)
		)
		(property "Value" "GND"
			(at 297.18 210.82 0)
			(effects
				(font
					(size 1.27 1.27)
					(thickness 0.15)
				)
			)
		)
		(property "Footprint" ""
			(at 306.07 213.36 0)
			(effects
				(font
					(size 1.27 1.27)
					(thickness 0.15)
				)
				(justify left bottom)
				(hide yes)
			)
		)
		(property "Datasheet" ""
			(at 306.07 218.44 0)
			(effects
				(font
					(size 1.27 1.27)
					(thickness 0.15)
				)
				(justify left bottom)
				(hide yes)
			)
		)
		(property "Description" ""
			(at 297.18 205.74 0)
			(effects
				(font
					(size 1.27 1.27)
				)
				(hide yes)
			)
		)
		(property "Author" "Antmicro"
			(at 306.07 213.36 0)
			(effects
				(font
					(size 1.27 1.27)
					(thickness 0.15)
				)
				(justify left bottom)
				(hide yes)
			)
		)
		(property "License" "Apache-2.0"
			(at 306.07 215.9 0)
			(effects
				(font
					(size 1.27 1.27)
					(thickness 0.15)
				)
				(justify left bottom)
				(hide yes)
			)
		)
		(pin "1"
		)
		(instances
			(project "sdi-mipi-video-converter"
				(path ""
					(reference "#PWR050")
					(unit 1)
				)
			)
		)
	)
	(symbol
		(lib_id "antmicroTestPoints:TP_0.75mm_SMD")
		(at 227.33 190.5 270)
		(unit 1)
		(exclude_from_sim no)
		(in_bom yes)
		(on_board yes)
		(dnp no)
		(fields_autoplaced yes)
		(property "Reference" "TP6"
			(at 229.87 193.675 90)
			(effects
				(font
					(size 1.27 1.27)
					(thickness 0.15)
				)
				(justify left)
			)
		)
		(property "Value" "TP_0.75mm_SMD"
			(at 219.71 208.28 0)
			(effects
				(font
					(size 1.27 1.27)
					(thickness 0.15)
				)
				(justify left bottom)
				(hide yes)
			)
		)
		(property "Footprint" "antmicro-footprints:TP_SMD_0.75mm"
			(at 217.17 208.28 0)
			(effects
				(font
					(size 1.27 1.27)
					(thickness 0.15)
				)
				(justify left bottom)
				(hide yes)
			)
		)
		(property "Datasheet" ""
			(at 214.63 208.28 0)
			(effects
				(font
					(size 1.27 1.27)
					(thickness 0.15)
				)
				(justify left bottom)
				(hide yes)
			)
		)
		(property "Description" "SMT test point"
			(at 227.33 190.5 0)
			(effects
				(font
					(size 1.27 1.27)
				)
				(hide yes)
			)
		)
		(property "MPN" ""
			(at 212.09 208.28 0)
			(effects
				(font
					(size 1.27 1.27)
					(thickness 0.15)
				)
				(justify left bottom)
				(hide yes)
			)
		)
		(property "Manufacturer" ""
			(at 209.55 208.28 0)
			(effects
				(font
					(size 1.27 1.27)
					(thickness 0.15)
				)
				(justify left bottom)
				(hide yes)
			)
		)
		(property "Author" "Antmicro"
			(at 207.01 208.28 0)
			(effects
				(font
					(size 1.27 1.27)
					(thickness 0.15)
				)
				(justify left bottom)
				(hide yes)
			)
		)
		(property "License" "Apache-2.0"
			(at 204.47 208.28 0)
			(effects
				(font
					(size 1.27 1.27)
					(thickness 0.15)
				)
				(justify left bottom)
				(hide yes)
			)
		)
		(pin "1"
		)
		(instances
			(project "sdi-mipi-video-converter"
				(path ""
					(reference "TP6")
					(unit 1)
				)
			)
		)
	)
	(symbol
		(lib_id "antmicroResistors0402:R_10k_0402")
		(at 59.69 102.87 270)
		(mirror x)
		(unit 1)
		(exclude_from_sim no)
		(in_bom yes)
		(on_board yes)
		(dnp no)
		(fields_autoplaced yes)
		(property "Reference" "R9"
			(at 62.23 99.0599 90)
			(effects
				(font
					(size 1.27 1.27)
					(thickness 0.15)
				)
				(justify left)
			)
		)
		(property "Value" "R_10k_0402"
			(at 46.99 82.55 0)
			(effects
				(font
					(size 1.27 1.27)
					(thickness 0.15)
				)
				(justify left bottom)
				(hide yes)
			)
		)
		(property "Footprint" "antmicro-footprints:R_0402_1005Metric"
			(at 44.45 82.55 0)
			(effects
				(font
					(size 1.27 1.27)
					(thickness 0.15)
				)
				(justify left bottom)
				(hide yes)
			)
		)
		(property "Datasheet" "https://www.bourns.com/docs/product-datasheets/cr.pdf"
			(at 41.91 82.55 0)
			(effects
				(font
					(size 1.27 1.27)
					(thickness 0.15)
				)
				(justify left bottom)
				(hide yes)
			)
		)
		(property "Description" "SMD Chip Resistor, 10 kohm, ± 1%, 62.5 mW, 0402 [1005 Metric], Thick Film, General Purpose"
			(at 59.69 102.87 0)
			(effects
				(font
					(size 1.27 1.27)
				)
				(hide yes)
			)
		)
		(property "Manufacturer" "Bourns"
			(at 36.83 82.55 0)
			(effects
				(font
					(size 1.27 1.27)
					(thickness 0.15)
				)
				(justify left bottom)
				(hide yes)
			)
		)
		(property "MPN" "CR0402-FX-1002GLF"
			(at 39.37 82.55 0)
			(effects
				(font
					(size 1.27 1.27)
					(thickness 0.15)
				)
				(justify left bottom)
				(hide yes)
			)
		)
		(property "Val" "10k"
			(at 62.23 101.5999 90)
			(effects
				(font
					(size 1.27 1.27)
					(thickness 0.15)
				)
				(justify left)
			)
		)
		(property "License" "Apache-2.0"
			(at 34.29 82.55 0)
			(effects
				(font
					(size 1.27 1.27)
					(thickness 0.15)
				)
				(justify left bottom)
				(hide yes)
			)
		)
		(property "Author" "Antmicro"
			(at 31.75 82.55 0)
			(effects
				(font
					(size 1.27 1.27)
					(thickness 0.15)
				)
				(justify left bottom)
				(hide yes)
			)
		)
		(property "Tolerance" "1%"
			(at 49.53 82.55 0)
			(effects
				(font
					(size 1.27 1.27)
				)
				(justify left bottom)
				(hide yes)
			)
		)
		(pin "1"
		)
		(pin "2"
		)
		(instances
			(project "sdi-mipi-video-converter"
				(path ""
					(reference "R9")
					(unit 1)
				)
			)
		)
	)
	(symbol
		(lib_id "antmicroCapacitors0603:C_1u_0603")
		(at 359.41 204.47 90)
		(unit 1)
		(exclude_from_sim no)
		(in_bom yes)
		(on_board yes)
		(dnp no)
		(fields_autoplaced yes)
		(property "Reference" "C30"
			(at 361.95 200.6535 90)
			(effects
				(font
					(size 1.27 1.27)
					(thickness 0.15)
				)
				(justify right)
			)
		)
		(property "Value" "C_1u_0603"
			(at 369.57 184.15 0)
			(effects
				(font
					(size 1.27 1.27)
					(thickness 0.15)
				)
				(justify left bottom)
				(hide yes)
			)
		)
		(property "Footprint" "antmicro-footprints:C_0603_1608Metric"
			(at 372.11 184.15 0)
			(effects
				(font
					(size 1.27 1.27)
					(thickness 0.15)
				)
				(justify left bottom)
				(hide yes)
			)
		)
		(property "Datasheet" "https://spicat.kyocera-avx.com/product/mlcc/chartview/0603YD105KAT2A/"
			(at 374.65 184.15 0)
			(effects
				(font
					(size 1.27 1.27)
					(thickness 0.15)
				)
				(justify left bottom)
				(hide yes)
			)
		)
		(property "Description" "SMD Multilayer Ceramic Capacitor, 1 µF, 16 V, 0603 [1608 Metric], ± 10%, X5R, AVX 0603 MLCC"
			(at 359.41 204.47 0)
			(effects
				(font
					(size 1.27 1.27)
				)
				(hide yes)
			)
		)
		(property "Manufacturer" "KYOCERA AVX"
			(at 379.73 184.15 0)
			(effects
				(font
					(size 1.27 1.27)
					(thickness 0.15)
				)
				(justify left bottom)
				(hide yes)
			)
		)
		(property "MPN" "0603YD105KAT2A"
			(at 377.19 184.15 0)
			(effects
				(font
					(size 1.27 1.27)
					(thickness 0.15)
				)
				(justify left bottom)
				(hide yes)
			)
		)
		(property "Val" "1u"
			(at 361.95 203.1935 90)
			(effects
				(font
					(size 1.27 1.27)
					(thickness 0.15)
				)
				(justify right)
			)
		)
		(property "License" "Apache-2.0"
			(at 382.27 184.15 0)
			(effects
				(font
					(size 1.27 1.27)
					(thickness 0.15)
				)
				(justify left bottom)
				(hide yes)
			)
		)
		(property "Author" "Antmicro"
			(at 384.81 184.15 0)
			(effects
				(font
					(size 1.27 1.27)
					(thickness 0.15)
				)
				(justify left bottom)
				(hide yes)
			)
		)
		(property "Voltage" ""
			(at 387.35 184.15 0)
			(effects
				(font
					(size 1.27 1.27)
				)
				(justify left bottom)
				(hide yes)
			)
		)
		(property "Dielectric" ""
			(at 389.89 184.15 0)
			(effects
				(font
					(size 1.27 1.27)
				)
				(justify left bottom)
				(hide yes)
			)
		)
		(pin "1"
		)
		(pin "2"
		)
		(instances
			(project "sdi-mipi-video-converter"
				(path ""
					(reference "C30")
					(unit 1)
				)
			)
		)
	)
	(symbol
		(lib_id "antmicropower:GND")
		(at 269.24 83.82 0)
		(unit 1)
		(exclude_from_sim no)
		(in_bom yes)
		(on_board yes)
		(dnp no)
		(fields_autoplaced yes)
		(property "Reference" "#PWR036"
			(at 278.13 86.36 0)
			(effects
				(font
					(size 1.27 1.27)
					(thickness 0.15)
				)
				(justify left bottom)
				(hide yes)
			)
		)
		(property "Value" "GND"
			(at 269.24 88.9 0)
			(effects
				(font
					(size 1.27 1.27)
					(thickness 0.15)
				)
			)
		)
		(property "Footprint" ""
			(at 278.13 91.44 0)
			(effects
				(font
					(size 1.27 1.27)
					(thickness 0.15)
				)
				(justify left bottom)
				(hide yes)
			)
		)
		(property "Datasheet" ""
			(at 278.13 96.52 0)
			(effects
				(font
					(size 1.27 1.27)
					(thickness 0.15)
				)
				(justify left bottom)
				(hide yes)
			)
		)
		(property "Description" ""
			(at 269.24 83.82 0)
			(effects
				(font
					(size 1.27 1.27)
				)
				(hide yes)
			)
		)
		(property "Author" "Antmicro"
			(at 278.13 91.44 0)
			(effects
				(font
					(size 1.27 1.27)
					(thickness 0.15)
				)
				(justify left bottom)
				(hide yes)
			)
		)
		(property "License" "Apache-2.0"
			(at 278.13 93.98 0)
			(effects
				(font
					(size 1.27 1.27)
					(thickness 0.15)
				)
				(justify left bottom)
				(hide yes)
			)
		)
		(pin "1"
		)
		(instances
			(project "sdi-mipi-video-converter"
				(path ""
					(reference "#PWR036")
					(unit 1)
				)
			)
		)
	)
	(symbol
		(lib_id "antmicroPMICVoltageRegulatorsLinear:AP7330-W5-7")
		(at 317.5 161.29 0)
		(unit 1)
		(exclude_from_sim no)
		(in_bom yes)
		(on_board yes)
		(dnp no)
		(fields_autoplaced yes)
		(property "Reference" "U8"
			(at 325.12 154.94 0)
			(effects
				(font
					(size 1.27 1.27)
					(thickness 0.15)
				)
			)
		)
		(property "Value" "AP7330-W5-7"
			(at 325.12 157.48 0)
			(effects
				(font
					(size 1.27 1.27)
					(thickness 0.15)
				)
			)
		)
		(property "Footprint" "antmicro-footprints:SOT-23-5"
			(at 347.98 171.45 0)
			(effects
				(font
					(size 1.27 1.27)
					(thickness 0.15)
				)
				(justify left bottom)
				(hide yes)
			)
		)
		(property "Datasheet" "https://www.diodes.com/assets/Datasheets/AP7330.pdf"
			(at 347.98 173.99 0)
			(effects
				(font
					(size 1.27 1.27)
					(thickness 0.15)
				)
				(justify left bottom)
				(hide yes)
			)
		)
		(property "Description" "Voltage regulator"
			(at 317.5 161.29 0)
			(effects
				(font
					(size 1.27 1.27)
				)
				(hide yes)
			)
		)
		(property "MPN" "AP7330-W5-7"
			(at 347.98 176.53 0)
			(effects
				(font
					(size 1.27 1.27)
					(thickness 0.15)
				)
				(justify left bottom)
				(hide yes)
			)
		)
		(property "Manufacturer" "Diodes Incorporated"
			(at 347.98 179.07 0)
			(effects
				(font
					(size 1.27 1.27)
					(thickness 0.15)
				)
				(justify left bottom)
				(hide yes)
			)
		)
		(property "Author" "Antmicro"
			(at 347.98 181.61 0)
			(effects
				(font
					(size 1.27 1.27)
					(thickness 0.15)
				)
				(justify left bottom)
				(hide yes)
			)
		)
		(property "License" "Apache-2.0"
			(at 347.98 184.15 0)
			(effects
				(font
					(size 1.27 1.27)
					(thickness 0.15)
				)
				(justify left bottom)
				(hide yes)
			)
		)
		(pin "1"
		)
		(pin "2"
		)
		(pin "3"
		)
		(pin "4"
		)
		(pin "5"
		)
		(instances
			(project "sdi-mipi-video-converter"
				(path ""
					(reference "U8")
					(unit 1)
				)
			)
		)
	)
	(symbol
		(lib_id "antmicroOperationalAmplifiers:LM339_TSSOP_CUSTOM_Split")
		(at 154.94 231.14 0)
		(unit 3)
		(exclude_from_sim no)
		(in_bom yes)
		(on_board yes)
		(dnp no)
		(fields_autoplaced yes)
		(property "Reference" "U2"
			(at 160.02 224.79 0)
			(effects
				(font
					(size 1.27 1.27)
					(thickness 0.15)
				)
			)
		)
		(property "Value" "LM339_TSSOP_Split"
			(at 160.02 224.79 0)
			(effects
				(font
					(size 1.27 1.27)
					(thickness 0.15)
				)
				(hide yes)
			)
		)
		(property "Footprint" "antmicro-footprints:TSSOP-14_4.4x5mm_P0.65mm"
			(at 180.34 241.3 0)
			(effects
				(font
					(size 1.27 1.27)
					(thickness 0.15)
				)
				(justify left bottom)
				(hide yes)
			)
		)
		(property "Datasheet" "https://www.ti.com/lit/ds/symlink/lm339b.pdf?ts=1679641364820&ref_url=https%253A%252F%252Fwww.google.com%252F"
			(at 180.34 243.84 0)
			(effects
				(font
					(size 1.27 1.27)
					(thickness 0.15)
				)
				(justify left bottom)
				(hide yes)
			)
		)
		(property "Description" "Analogue Comparator, Differential, 4 Comparators, 300 ns, 2V to 36V, TSSOP, 14 Pins"
			(at 180.34 256.54 0)
			(effects
				(font
					(size 1.27 1.27)
				)
				(justify left bottom)
				(hide yes)
			)
		)
		(property "MPN" "LM339PW"
			(at 160.02 227.33 0)
			(effects
				(font
					(size 1.27 1.27)
					(thickness 0.15)
				)
			)
		)
		(property "Manufacturer" "Texas Instruments"
			(at 180.34 248.92 0)
			(effects
				(font
					(size 1.27 1.27)
					(thickness 0.15)
				)
				(justify left bottom)
				(hide yes)
			)
		)
		(property "Author" "Antmicro"
			(at 180.34 251.46 0)
			(effects
				(font
					(size 1.27 1.27)
					(thickness 0.15)
				)
				(justify left bottom)
				(hide yes)
			)
		)
		(property "License" "Apache-2.0"
			(at 180.34 254 0)
			(effects
				(font
					(size 1.27 1.27)
					(thickness 0.15)
				)
				(justify left bottom)
				(hide yes)
			)
		)
		(pin "2"
		)
		(pin "4"
		)
		(pin "5"
		)
		(pin "1"
		)
		(pin "6"
		)
		(pin "7"
		)
		(pin "14"
		)
		(pin "8"
		)
		(pin "9"
		)
		(pin "10"
		)
		(pin "11"
		)
		(pin "13"
		)
		(pin "12"
		)
		(pin "3"
		)
		(instances
			(project "sdi-mipi-video-converter"
				(path ""
					(reference "U2")
					(unit 3)
				)
			)
		)
	)
	(symbol
		(lib_id "antmicropower:+1V8")
		(at 180.34 229.87 0)
		(unit 1)
		(exclude_from_sim no)
		(in_bom yes)
		(on_board yes)
		(dnp no)
		(fields_autoplaced yes)
		(property "Reference" "#PWR026"
			(at 195.58 232.41 0)
			(effects
				(font
					(size 1.27 1.27)
					(thickness 0.15)
				)
				(justify left bottom)
				(hide yes)
			)
		)
		(property "Value" "+1V8"
			(at 180.34 224.79 0)
			(effects
				(font
					(size 1.27 1.27)
					(thickness 0.15)
				)
			)
		)
		(property "Footprint" ""
			(at 195.58 237.49 0)
			(effects
				(font
					(size 1.27 1.27)
					(thickness 0.15)
				)
				(justify left bottom)
				(hide yes)
			)
		)
		(property "Datasheet" ""
			(at 195.58 240.03 0)
			(effects
				(font
					(size 1.27 1.27)
					(thickness 0.15)
				)
				(justify left bottom)
				(hide yes)
			)
		)
		(property "Description" ""
			(at 180.34 229.87 0)
			(effects
				(font
					(size 1.27 1.27)
				)
				(hide yes)
			)
		)
		(property "Author" "Antmicro"
			(at 195.58 237.49 0)
			(effects
				(font
					(size 1.27 1.27)
					(thickness 0.15)
				)
				(justify left bottom)
				(hide yes)
			)
		)
		(property "License" "Apache-2.0"
			(at 195.58 240.03 0)
			(effects
				(font
					(size 1.27 1.27)
					(thickness 0.15)
				)
				(justify left bottom)
				(hide yes)
			)
		)
		(pin "1"
		)
		(instances
			(project "sdi-mipi-video-converter"
				(path ""
					(reference "#PWR026")
					(unit 1)
				)
			)
		)
	)
	(symbol
		(lib_id "antmicroCapacitors0603:C_22u_0603")
		(at 355.6 85.09 90)
		(unit 1)
		(exclude_from_sim no)
		(in_bom yes)
		(on_board yes)
		(dnp no)
		(fields_autoplaced yes)
		(property "Reference" "C20"
			(at 358.14 81.2735 90)
			(effects
				(font
					(size 1.27 1.27)
					(thickness 0.15)
				)
				(justify right)
			)
		)
		(property "Value" "C_22u_0603"
			(at 365.76 64.77 0)
			(effects
				(font
					(size 1.27 1.27)
					(thickness 0.15)
				)
				(justify left bottom)
				(hide yes)
			)
		)
		(property "Footprint" "antmicro-footprints:C_0603_1608Metric"
			(at 368.3 64.77 0)
			(effects
				(font
					(size 1.27 1.27)
					(thickness 0.15)
				)
				(justify left bottom)
				(hide yes)
			)
		)
		(property "Datasheet" "https://www.murata.com/products/productdetail?partno=GRM188R60J226MEA0%23"
			(at 370.84 64.77 0)
			(effects
				(font
					(size 1.27 1.27)
					(thickness 0.15)
				)
				(justify left bottom)
				(hide yes)
			)
		)
		(property "Description" "SMD Multilayer Ceramic Capacitor, 22 µF, 6.3 V, 0603 [1608 Metric], ± 20%, X5R, GRM Series"
			(at 355.6 85.09 0)
			(effects
				(font
					(size 1.27 1.27)
				)
				(hide yes)
			)
		)
		(property "Manufacturer" "Murata"
			(at 375.92 64.77 0)
			(effects
				(font
					(size 1.27 1.27)
					(thickness 0.15)
				)
				(justify left bottom)
				(hide yes)
			)
		)
		(property "MPN" "GRM188R60J226MEA0D"
			(at 373.38 64.77 0)
			(effects
				(font
					(size 1.27 1.27)
					(thickness 0.15)
				)
				(justify left bottom)
				(hide yes)
			)
		)
		(property "Val" "22u"
			(at 358.14 83.8135 90)
			(effects
				(font
					(size 1.27 1.27)
					(thickness 0.15)
				)
				(justify right)
			)
		)
		(property "License" "Apache-2.0"
			(at 378.46 64.77 0)
			(effects
				(font
					(size 1.27 1.27)
					(thickness 0.15)
				)
				(justify left bottom)
				(hide yes)
			)
		)
		(property "Author" "Antmicro"
			(at 381 64.77 0)
			(effects
				(font
					(size 1.27 1.27)
					(thickness 0.15)
				)
				(justify left bottom)
				(hide yes)
			)
		)
		(property "Voltage" ""
			(at 383.54 64.77 0)
			(effects
				(font
					(size 1.27 1.27)
				)
				(justify left bottom)
				(hide yes)
			)
		)
		(property "Dielectric" ""
			(at 386.08 64.77 0)
			(effects
				(font
					(size 1.27 1.27)
				)
				(justify left bottom)
				(hide yes)
			)
		)
		(pin "1"
		)
		(pin "2"
		)
		(instances
			(project "sdi-mipi-video-converter"
				(path ""
					(reference "C20")
					(unit 1)
				)
			)
		)
	)
	(symbol
		(lib_id "antmicropower:+5V")
		(at 123.19 74.93 0)
		(unit 1)
		(exclude_from_sim no)
		(in_bom yes)
		(on_board yes)
		(dnp no)
		(fields_autoplaced yes)
		(property "Reference" "#PWR024"
			(at 138.43 77.47 0)
			(effects
				(font
					(size 1.27 1.27)
					(thickness 0.15)
				)
				(justify left bottom)
				(hide yes)
			)
		)
		(property "Value" "+5V"
			(at 123.19 69.85 0)
			(effects
				(font
					(size 1.27 1.27)
					(thickness 0.15)
				)
			)
		)
		(property "Footprint" ""
			(at 138.43 82.55 0)
			(effects
				(font
					(size 1.27 1.27)
					(thickness 0.15)
				)
				(justify left bottom)
				(hide yes)
			)
		)
		(property "Datasheet" ""
			(at 138.43 85.09 0)
			(effects
				(font
					(size 1.27 1.27)
					(thickness 0.15)
				)
				(justify left bottom)
				(hide yes)
			)
		)
		(property "Description" ""
			(at 123.19 74.93 0)
			(effects
				(font
					(size 1.27 1.27)
				)
				(hide yes)
			)
		)
		(property "Author" "Antmicro"
			(at 138.43 82.55 0)
			(effects
				(font
					(size 1.27 1.27)
					(thickness 0.15)
				)
				(justify left bottom)
				(hide yes)
			)
		)
		(property "License" "Apache-2.0"
			(at 138.43 85.09 0)
			(effects
				(font
					(size 1.27 1.27)
					(thickness 0.15)
				)
				(justify left bottom)
				(hide yes)
			)
		)
		(pin "1"
		)
		(instances
			(project "sdi-mipi-video-converter"
				(path ""
					(reference "#PWR024")
					(unit 1)
				)
			)
		)
	)
	(symbol
		(lib_id "antmicroResistors0402:R_33k_0402")
		(at 337.82 46.99 90)
		(unit 1)
		(exclude_from_sim no)
		(in_bom yes)
		(on_board yes)
		(dnp no)
		(fields_autoplaced yes)
		(property "Reference" "R26"
			(at 340.36 43.1799 90)
			(effects
				(font
					(size 1.27 1.27)
					(thickness 0.15)
				)
				(justify right)
			)
		)
		(property "Value" "R_33k_0402"
			(at 350.52 26.67 0)
			(effects
				(font
					(size 1.27 1.27)
					(thickness 0.15)
				)
				(justify left bottom)
				(hide yes)
			)
		)
		(property "Footprint" "antmicro-footprints:R_0402_1005Metric"
			(at 353.06 26.67 0)
			(effects
				(font
					(size 1.27 1.27)
					(thickness 0.15)
				)
				(justify left bottom)
				(hide yes)
			)
		)
		(property "Datasheet" "https://www.bourns.com/docs/product-datasheets/cr.pdf"
			(at 355.6 26.67 0)
			(effects
				(font
					(size 1.27 1.27)
					(thickness 0.15)
				)
				(justify left bottom)
				(hide yes)
			)
		)
		(property "Description" "SMD Chip Resistor, 33 kohm, ± 1%, 62.5 mW, 0402 [1005 Metric], Thick Film, General Purpose"
			(at 337.82 46.99 0)
			(effects
				(font
					(size 1.27 1.27)
				)
				(hide yes)
			)
		)
		(property "Manufacturer" "Bourns"
			(at 360.68 26.67 0)
			(effects
				(font
					(size 1.27 1.27)
					(thickness 0.15)
				)
				(justify left bottom)
				(hide yes)
			)
		)
		(property "MPN" "CR0402-FX-3302GLF"
			(at 358.14 26.67 0)
			(effects
				(font
					(size 1.27 1.27)
					(thickness 0.15)
				)
				(justify left bottom)
				(hide yes)
			)
		)
		(property "Val" "33k"
			(at 340.36 45.7199 90)
			(effects
				(font
					(size 1.27 1.27)
					(thickness 0.15)
				)
				(justify right)
			)
		)
		(property "License" "Apache-2.0"
			(at 363.22 26.67 0)
			(effects
				(font
					(size 1.27 1.27)
					(thickness 0.15)
				)
				(justify left bottom)
				(hide yes)
			)
		)
		(property "Author" "Antmicro"
			(at 365.76 26.67 0)
			(effects
				(font
					(size 1.27 1.27)
					(thickness 0.15)
				)
				(justify left bottom)
				(hide yes)
			)
		)
		(property "Tolerance" "1%"
			(at 347.98 26.67 0)
			(effects
				(font
					(size 1.27 1.27)
				)
				(justify left bottom)
				(hide yes)
			)
		)
		(pin "1"
		)
		(pin "2"
		)
		(instances
			(project "sdi-mipi-video-converter"
				(path ""
					(reference "R26")
					(unit 1)
				)
			)
		)
	)
	(symbol
		(lib_id "antmicropower:GND")
		(at 48.26 143.51 0)
		(unit 1)
		(exclude_from_sim no)
		(in_bom yes)
		(on_board yes)
		(dnp no)
		(fields_autoplaced yes)
		(property "Reference" "#PWR0104"
			(at 57.15 146.05 0)
			(effects
				(font
					(size 1.27 1.27)
					(thickness 0.15)
				)
				(justify left bottom)
				(hide yes)
			)
		)
		(property "Value" "GND"
			(at 48.26 148.59 0)
			(effects
				(font
					(size 1.27 1.27)
					(thickness 0.15)
				)
			)
		)
		(property "Footprint" ""
			(at 57.15 151.13 0)
			(effects
				(font
					(size 1.27 1.27)
					(thickness 0.15)
				)
				(justify left bottom)
				(hide yes)
			)
		)
		(property "Datasheet" ""
			(at 57.15 156.21 0)
			(effects
				(font
					(size 1.27 1.27)
					(thickness 0.15)
				)
				(justify left bottom)
				(hide yes)
			)
		)
		(property "Description" ""
			(at 48.26 143.51 0)
			(effects
				(font
					(size 1.27 1.27)
				)
				(hide yes)
			)
		)
		(property "Author" "Antmicro"
			(at 57.15 151.13 0)
			(effects
				(font
					(size 1.27 1.27)
					(thickness 0.15)
				)
				(justify left bottom)
				(hide yes)
			)
		)
		(property "License" "Apache-2.0"
			(at 57.15 153.67 0)
			(effects
				(font
					(size 1.27 1.27)
					(thickness 0.15)
				)
				(justify left bottom)
				(hide yes)
			)
		)
		(pin "1"
		)
		(instances
			(project "sdi-mipi-video-converter"
				(path ""
					(reference "#PWR0104")
					(unit 1)
				)
			)
		)
	)
	(symbol
		(lib_id "antmicroCapacitors0603:C_10u_0603")
		(at 269.24 81.28 90)
		(unit 1)
		(exclude_from_sim no)
		(in_bom yes)
		(on_board yes)
		(dnp no)
		(fields_autoplaced yes)
		(property "Reference" "C11"
			(at 266.7 77.4635 90)
			(effects
				(font
					(size 1.27 1.27)
					(thickness 0.15)
				)
				(justify left)
			)
		)
		(property "Value" "C_10u_0603"
			(at 279.4 60.96 0)
			(effects
				(font
					(size 1.27 1.27)
					(thickness 0.15)
				)
				(justify left bottom)
				(hide yes)
			)
		)
		(property "Footprint" "antmicro-footprints:C_0603_1608Metric"
			(at 281.94 60.96 0)
			(effects
				(font
					(size 1.27 1.27)
					(thickness 0.15)
				)
				(justify left bottom)
				(hide yes)
			)
		)
		(property "Datasheet" "https://www.murata.com/products/productdetail?partno=GRM188R61A106KE69%23"
			(at 284.48 60.96 0)
			(effects
				(font
					(size 1.27 1.27)
					(thickness 0.15)
				)
				(justify left bottom)
				(hide yes)
			)
		)
		(property "Description" "SMD Multilayer Ceramic Capacitor, 10 µF, 10 V, 0603 [1608 Metric], ± 10%, X5R, GRM Series"
			(at 269.24 81.28 0)
			(effects
				(font
					(size 1.27 1.27)
				)
				(hide yes)
			)
		)
		(property "Manufacturer" "Murata"
			(at 289.56 60.96 0)
			(effects
				(font
					(size 1.27 1.27)
					(thickness 0.15)
				)
				(justify left bottom)
				(hide yes)
			)
		)
		(property "MPN" "GRM188R61A106KE69D"
			(at 287.02 60.96 0)
			(effects
				(font
					(size 1.27 1.27)
					(thickness 0.15)
				)
				(justify left bottom)
				(hide yes)
			)
		)
		(property "Val" "10u"
			(at 266.7 80.0035 90)
			(effects
				(font
					(size 1.27 1.27)
					(thickness 0.15)
				)
				(justify left)
			)
		)
		(property "License" "Apache-2.0"
			(at 292.1 60.96 0)
			(effects
				(font
					(size 1.27 1.27)
					(thickness 0.15)
				)
				(justify left bottom)
				(hide yes)
			)
		)
		(property "Author" "Antmicro"
			(at 294.64 60.96 0)
			(effects
				(font
					(size 1.27 1.27)
					(thickness 0.15)
				)
				(justify left bottom)
				(hide yes)
			)
		)
		(property "Voltage" ""
			(at 297.18 60.96 0)
			(effects
				(font
					(size 1.27 1.27)
				)
				(justify left bottom)
				(hide yes)
			)
		)
		(property "Dielectric" "template_dielectric"
			(at 299.72 60.96 0)
			(effects
				(font
					(size 1.27 1.27)
				)
				(justify left bottom)
				(hide yes)
			)
		)
		(pin "1"
		)
		(pin "2"
		)
		(instances
			(project "sdi-mipi-video-converter"
				(path ""
					(reference "C11")
					(unit 1)
				)
			)
		)
	)
	(symbol
		(lib_id "antmicropower:+1V5")
		(at 403.86 104.14 0)
		(unit 1)
		(exclude_from_sim no)
		(in_bom yes)
		(on_board yes)
		(dnp no)
		(fields_autoplaced yes)
		(property "Reference" "#PWR0227"
			(at 403.86 107.95 0)
			(effects
				(font
					(size 1.27 1.27)
				)
				(hide yes)
			)
		)
		(property "Value" "+1V5"
			(at 403.86 99.06 0)
			(effects
				(font
					(size 1.27 1.27)
				)
			)
		)
		(property "Footprint" ""
			(at 403.86 104.14 0)
			(effects
				(font
					(size 1.27 1.27)
				)
				(hide yes)
			)
		)
		(property "Datasheet" ""
			(at 403.86 104.14 0)
			(effects
				(font
					(size 1.27 1.27)
				)
				(hide yes)
			)
		)
		(property "Description" ""
			(at 403.86 104.14 0)
			(effects
				(font
					(size 1.27 1.27)
				)
				(hide yes)
			)
		)
		(pin "1"
		)
		(instances
			(project "sdi-mipi-video-converter"
				(path ""
					(reference "#PWR0227")
					(unit 1)
				)
			)
		)
	)
	(symbol
		(lib_id "antmicropower:GND")
		(at 325.12 207.01 0)
		(unit 1)
		(exclude_from_sim no)
		(in_bom yes)
		(on_board yes)
		(dnp no)
		(fields_autoplaced yes)
		(property "Reference" "#PWR057"
			(at 334.01 209.55 0)
			(effects
				(font
					(size 1.27 1.27)
					(thickness 0.15)
				)
				(justify left bottom)
				(hide yes)
			)
		)
		(property "Value" "GND"
			(at 325.12 212.09 0)
			(effects
				(font
					(size 1.27 1.27)
					(thickness 0.15)
				)
			)
		)
		(property "Footprint" ""
			(at 334.01 214.63 0)
			(effects
				(font
					(size 1.27 1.27)
					(thickness 0.15)
				)
				(justify left bottom)
				(hide yes)
			)
		)
		(property "Datasheet" ""
			(at 334.01 219.71 0)
			(effects
				(font
					(size 1.27 1.27)
					(thickness 0.15)
				)
				(justify left bottom)
				(hide yes)
			)
		)
		(property "Description" ""
			(at 325.12 207.01 0)
			(effects
				(font
					(size 1.27 1.27)
				)
				(hide yes)
			)
		)
		(property "Author" "Antmicro"
			(at 334.01 214.63 0)
			(effects
				(font
					(size 1.27 1.27)
					(thickness 0.15)
				)
				(justify left bottom)
				(hide yes)
			)
		)
		(property "License" "Apache-2.0"
			(at 334.01 217.17 0)
			(effects
				(font
					(size 1.27 1.27)
					(thickness 0.15)
				)
				(justify left bottom)
				(hide yes)
			)
		)
		(pin "1"
		)
		(instances
			(project "sdi-mipi-video-converter"
				(path ""
					(reference "#PWR057")
					(unit 1)
				)
			)
		)
	)
	(symbol
		(lib_id "antmicropower:+3.3V")
		(at 53.34 127 0)
		(unit 1)
		(exclude_from_sim no)
		(in_bom yes)
		(on_board yes)
		(dnp no)
		(fields_autoplaced yes)
		(property "Reference" "#PWR0237"
			(at 53.34 130.81 0)
			(effects
				(font
					(size 1.27 1.27)
				)
				(hide yes)
			)
		)
		(property "Value" "+3V3"
			(at 50.8 125.7299 0)
			(effects
				(font
					(size 1.27 1.27)
				)
				(justify right)
			)
		)
		(property "Footprint" ""
			(at 53.34 127 0)
			(effects
				(font
					(size 1.27 1.27)
				)
				(hide yes)
			)
		)
		(property "Datasheet" ""
			(at 53.34 127 0)
			(effects
				(font
					(size 1.27 1.27)
				)
				(hide yes)
			)
		)
		(property "Description" ""
			(at 53.34 127 0)
			(effects
				(font
					(size 1.27 1.27)
				)
				(hide yes)
			)
		)
		(pin "1"
		)
		(instances
			(project "sdi-mipi-video-converter"
				(path ""
					(reference "#PWR0237")
					(unit 1)
				)
			)
		)
	)
	(symbol
		(lib_id "antmicroFixedInductors:L_3u3_6.6A_XEL4030")
		(at 325.12 39.37 0)
		(unit 1)
		(exclude_from_sim no)
		(in_bom yes)
		(on_board yes)
		(dnp no)
		(fields_autoplaced yes)
		(property "Reference" "L3"
			(at 327.66 34.29 0)
			(effects
				(font
					(size 1.27 1.27)
					(thickness 0.15)
				)
			)
		)
		(property "Value" "L_3u3_5.9A_XEL4030"
			(at 339.09 41.91 0)
			(effects
				(font
					(size 1.27 1.27)
					(thickness 0.15)
				)
				(justify left bottom)
				(hide yes)
			)
		)
		(property "Footprint" "antmicro-footprints:L_Coilcraft-XEL4030"
			(at 339.09 46.99 0)
			(effects
				(font
					(size 1.27 1.27)
					(thickness 0.15)
				)
				(justify left bottom)
				(hide yes)
			)
		)
		(property "Datasheet" "https://www.coilcraft.com/getmedia/8245f050-f190-4295-8c41-7c03d662ee3d/xel4030.pdf"
			(at 339.09 49.53 0)
			(effects
				(font
					(size 1.27 1.27)
					(thickness 0.15)
				)
				(justify left bottom)
				(hide yes)
			)
		)
		(property "Description" "Power Inductor (SMT), AEC-Q200, 3.3 µH, 6.6 A, Shielded, 5.9 A, XEL4030"
			(at 325.12 39.37 0)
			(effects
				(font
					(size 1.27 1.27)
				)
				(hide yes)
			)
		)
		(property "MPN" "XEL4030-332MEC"
			(at 339.09 54.61 0)
			(effects
				(font
					(size 1.27 1.27)
					(thickness 0.15)
				)
				(justify left bottom)
				(hide yes)
			)
		)
		(property "Manufacturer" "Coilcraft"
			(at 339.09 52.07 0)
			(effects
				(font
					(size 1.27 1.27)
					(thickness 0.15)
				)
				(justify left bottom)
				(hide yes)
			)
		)
		(property "Val" "3u3/6.6A"
			(at 327.66 36.83 0)
			(effects
				(font
					(size 1.27 1.27)
					(thickness 0.15)
				)
			)
		)
		(property "Size" "4.0x4.0"
			(at 339.09 62.23 0)
			(effects
				(font
					(size 1.27 1.27)
					(thickness 0.15)
				)
				(justify left bottom)
				(hide yes)
			)
		)
		(property "ISat" "5.9 A"
			(at 339.09 55.88 0)
			(effects
				(font
					(size 1.27 1.27)
				)
				(justify left)
				(hide yes)
			)
		)
		(property "IMax" "6.6 A"
			(at 339.09 59.69 0)
			(effects
				(font
					(size 1.27 1.27)
					(thickness 0.15)
				)
				(justify left bottom)
				(hide yes)
			)
		)
		(property "Author" "Antmicro"
			(at 339.09 64.77 0)
			(effects
				(font
					(size 1.27 1.27)
					(thickness 0.15)
				)
				(justify left bottom)
				(hide yes)
			)
		)
		(property "License" "Apache-2.0"
			(at 339.09 67.31 0)
			(effects
				(font
					(size 1.27 1.27)
					(thickness 0.15)
				)
				(justify left bottom)
				(hide yes)
			)
		)
		(pin "1"
		)
		(pin "2"
		)
		(instances
			(project "sdi-mipi-video-converter"
				(path ""
					(reference "L3")
					(unit 1)
				)
			)
		)
	)
	(symbol
		(lib_id "antmicropower:GND")
		(at 38.1 93.98 0)
		(unit 1)
		(exclude_from_sim no)
		(in_bom yes)
		(on_board yes)
		(dnp no)
		(fields_autoplaced yes)
		(property "Reference" "#PWR0243"
			(at 46.99 96.52 0)
			(effects
				(font
					(size 1.27 1.27)
					(thickness 0.15)
				)
				(justify left bottom)
				(hide yes)
			)
		)
		(property "Value" "GND"
			(at 38.1 99.06 0)
			(effects
				(font
					(size 1.27 1.27)
					(thickness 0.15)
				)
			)
		)
		(property "Footprint" ""
			(at 46.99 101.6 0)
			(effects
				(font
					(size 1.27 1.27)
					(thickness 0.15)
				)
				(justify left bottom)
				(hide yes)
			)
		)
		(property "Datasheet" ""
			(at 46.99 106.68 0)
			(effects
				(font
					(size 1.27 1.27)
					(thickness 0.15)
				)
				(justify left bottom)
				(hide yes)
			)
		)
		(property "Description" ""
			(at 38.1 93.98 0)
			(effects
				(font
					(size 1.27 1.27)
				)
				(hide yes)
			)
		)
		(property "Author" "Antmicro"
			(at 46.99 101.6 0)
			(effects
				(font
					(size 1.27 1.27)
					(thickness 0.15)
				)
				(justify left bottom)
				(hide yes)
			)
		)
		(property "License" "Apache-2.0"
			(at 46.99 104.14 0)
			(effects
				(font
					(size 1.27 1.27)
					(thickness 0.15)
				)
				(justify left bottom)
				(hide yes)
			)
		)
		(pin "1"
		)
		(instances
			(project "sdi-mipi-video-converter"
				(path ""
					(reference "#PWR0243")
					(unit 1)
				)
			)
		)
	)
	(symbol
		(lib_id "antmicropower:GND")
		(at 359.41 175.26 0)
		(unit 1)
		(exclude_from_sim no)
		(in_bom yes)
		(on_board yes)
		(dnp no)
		(fields_autoplaced yes)
		(property "Reference" "#PWR071"
			(at 368.3 177.8 0)
			(effects
				(font
					(size 1.27 1.27)
					(thickness 0.15)
				)
				(justify left bottom)
				(hide yes)
			)
		)
		(property "Value" "GND"
			(at 356.87 176.5299 0)
			(effects
				(font
					(size 1.27 1.27)
					(thickness 0.15)
				)
				(justify right)
			)
		)
		(property "Footprint" ""
			(at 368.3 182.88 0)
			(effects
				(font
					(size 1.27 1.27)
					(thickness 0.15)
				)
				(justify left bottom)
				(hide yes)
			)
		)
		(property "Datasheet" ""
			(at 368.3 187.96 0)
			(effects
				(font
					(size 1.27 1.27)
					(thickness 0.15)
				)
				(justify left bottom)
				(hide yes)
			)
		)
		(property "Description" ""
			(at 359.41 175.26 0)
			(effects
				(font
					(size 1.27 1.27)
				)
				(hide yes)
			)
		)
		(property "Author" "Antmicro"
			(at 368.3 182.88 0)
			(effects
				(font
					(size 1.27 1.27)
					(thickness 0.15)
				)
				(justify left bottom)
				(hide yes)
			)
		)
		(property "License" "Apache-2.0"
			(at 368.3 185.42 0)
			(effects
				(font
					(size 1.27 1.27)
					(thickness 0.15)
				)
				(justify left bottom)
				(hide yes)
			)
		)
		(pin "1"
		)
		(instances
			(project "sdi-mipi-video-converter"
				(path ""
					(reference "#PWR071")
					(unit 1)
				)
			)
		)
	)
	(symbol
		(lib_id "antmicropower:GND")
		(at 241.3 267.97 0)
		(unit 1)
		(exclude_from_sim no)
		(in_bom yes)
		(on_board yes)
		(dnp no)
		(fields_autoplaced yes)
		(property "Reference" "#PWR042"
			(at 250.19 270.51 0)
			(effects
				(font
					(size 1.27 1.27)
					(thickness 0.15)
				)
				(justify left bottom)
				(hide yes)
			)
		)
		(property "Value" "GND"
			(at 241.3 273.05 0)
			(effects
				(font
					(size 1.27 1.27)
					(thickness 0.15)
				)
			)
		)
		(property "Footprint" ""
			(at 250.19 275.59 0)
			(effects
				(font
					(size 1.27 1.27)
					(thickness 0.15)
				)
				(justify left bottom)
				(hide yes)
			)
		)
		(property "Datasheet" ""
			(at 250.19 280.67 0)
			(effects
				(font
					(size 1.27 1.27)
					(thickness 0.15)
				)
				(justify left bottom)
				(hide yes)
			)
		)
		(property "Description" ""
			(at 241.3 267.97 0)
			(effects
				(font
					(size 1.27 1.27)
				)
				(hide yes)
			)
		)
		(property "Author" "Antmicro"
			(at 250.19 275.59 0)
			(effects
				(font
					(size 1.27 1.27)
					(thickness 0.15)
				)
				(justify left bottom)
				(hide yes)
			)
		)
		(property "License" "Apache-2.0"
			(at 250.19 278.13 0)
			(effects
				(font
					(size 1.27 1.27)
					(thickness 0.15)
				)
				(justify left bottom)
				(hide yes)
			)
		)
		(pin "1"
		)
		(instances
			(project "sdi-mipi-video-converter"
				(path ""
					(reference "#PWR042")
					(unit 1)
				)
			)
		)
	)
	(symbol
		(lib_id "antmicropower:+1V5")
		(at 85.09 267.97 0)
		(unit 1)
		(exclude_from_sim no)
		(in_bom yes)
		(on_board yes)
		(dnp no)
		(fields_autoplaced yes)
		(property "Reference" "#PWR0102"
			(at 85.09 271.78 0)
			(effects
				(font
					(size 1.27 1.27)
				)
				(hide yes)
			)
		)
		(property "Value" "+1V5"
			(at 85.09 262.89 0)
			(effects
				(font
					(size 1.27 1.27)
				)
			)
		)
		(property "Footprint" ""
			(at 85.09 267.97 0)
			(effects
				(font
					(size 1.27 1.27)
				)
				(hide yes)
			)
		)
		(property "Datasheet" ""
			(at 85.09 267.97 0)
			(effects
				(font
					(size 1.27 1.27)
				)
				(hide yes)
			)
		)
		(property "Description" ""
			(at 85.09 267.97 0)
			(effects
				(font
					(size 1.27 1.27)
				)
				(hide yes)
			)
		)
		(pin "1"
		)
		(instances
			(project "sdi-mipi-video-converter"
				(path ""
					(reference "#PWR0102")
					(unit 1)
				)
			)
		)
	)
	(symbol
		(lib_id "antmicropower:+5V")
		(at 71.12 185.42 0)
		(unit 1)
		(exclude_from_sim no)
		(in_bom yes)
		(on_board yes)
		(dnp no)
		(fields_autoplaced yes)
		(property "Reference" "#PWR03"
			(at 86.36 187.96 0)
			(effects
				(font
					(size 1.27 1.27)
					(thickness 0.15)
				)
				(justify left bottom)
				(hide yes)
			)
		)
		(property "Value" "+5V"
			(at 71.12 180.34 0)
			(effects
				(font
					(size 1.27 1.27)
					(thickness 0.15)
				)
			)
		)
		(property "Footprint" ""
			(at 86.36 193.04 0)
			(effects
				(font
					(size 1.27 1.27)
					(thickness 0.15)
				)
				(justify left bottom)
				(hide yes)
			)
		)
		(property "Datasheet" ""
			(at 86.36 195.58 0)
			(effects
				(font
					(size 1.27 1.27)
					(thickness 0.15)
				)
				(justify left bottom)
				(hide yes)
			)
		)
		(property "Description" ""
			(at 71.12 185.42 0)
			(effects
				(font
					(size 1.27 1.27)
				)
				(hide yes)
			)
		)
		(property "Author" "Antmicro"
			(at 86.36 193.04 0)
			(effects
				(font
					(size 1.27 1.27)
					(thickness 0.15)
				)
				(justify left bottom)
				(hide yes)
			)
		)
		(property "License" "Apache-2.0"
			(at 86.36 195.58 0)
			(effects
				(font
					(size 1.27 1.27)
					(thickness 0.15)
				)
				(justify left bottom)
				(hide yes)
			)
		)
		(pin "1"
		)
		(instances
			(project "sdi-mipi-video-converter"
				(path ""
					(reference "#PWR03")
					(unit 1)
				)
			)
		)
	)
	(symbol
		(lib_id "antmicropower:GND")
		(at 345.44 175.26 0)
		(unit 1)
		(exclude_from_sim no)
		(in_bom yes)
		(on_board yes)
		(dnp no)
		(fields_autoplaced yes)
		(property "Reference" "#PWR065"
			(at 354.33 177.8 0)
			(effects
				(font
					(size 1.27 1.27)
					(thickness 0.15)
				)
				(justify left bottom)
				(hide yes)
			)
		)
		(property "Value" "GND"
			(at 345.44 180.34 0)
			(effects
				(font
					(size 1.27 1.27)
					(thickness 0.15)
				)
			)
		)
		(property "Footprint" ""
			(at 354.33 182.88 0)
			(effects
				(font
					(size 1.27 1.27)
					(thickness 0.15)
				)
				(justify left bottom)
				(hide yes)
			)
		)
		(property "Datasheet" ""
			(at 354.33 187.96 0)
			(effects
				(font
					(size 1.27 1.27)
					(thickness 0.15)
				)
				(justify left bottom)
				(hide yes)
			)
		)
		(property "Description" ""
			(at 345.44 175.26 0)
			(effects
				(font
					(size 1.27 1.27)
				)
				(hide yes)
			)
		)
		(property "Author" "Antmicro"
			(at 354.33 182.88 0)
			(effects
				(font
					(size 1.27 1.27)
					(thickness 0.15)
				)
				(justify left bottom)
				(hide yes)
			)
		)
		(property "License" "Apache-2.0"
			(at 354.33 185.42 0)
			(effects
				(font
					(size 1.27 1.27)
					(thickness 0.15)
				)
				(justify left bottom)
				(hide yes)
			)
		)
		(pin "1"
		)
		(instances
			(project "sdi-mipi-video-converter"
				(path ""
					(reference "#PWR065")
					(unit 1)
				)
			)
		)
	)
	(symbol
		(lib_id "antmicropower:GND")
		(at 325.12 241.3 0)
		(unit 1)
		(exclude_from_sim no)
		(in_bom yes)
		(on_board yes)
		(dnp no)
		(fields_autoplaced yes)
		(property "Reference" "#PWR058"
			(at 334.01 243.84 0)
			(effects
				(font
					(size 1.27 1.27)
					(thickness 0.15)
				)
				(justify left bottom)
				(hide yes)
			)
		)
		(property "Value" "GND"
			(at 325.12 246.38 0)
			(effects
				(font
					(size 1.27 1.27)
					(thickness 0.15)
				)
			)
		)
		(property "Footprint" ""
			(at 334.01 248.92 0)
			(effects
				(font
					(size 1.27 1.27)
					(thickness 0.15)
				)
				(justify left bottom)
				(hide yes)
			)
		)
		(property "Datasheet" ""
			(at 334.01 254 0)
			(effects
				(font
					(size 1.27 1.27)
					(thickness 0.15)
				)
				(justify left bottom)
				(hide yes)
			)
		)
		(property "Description" ""
			(at 325.12 241.3 0)
			(effects
				(font
					(size 1.27 1.27)
				)
				(hide yes)
			)
		)
		(property "Author" "Antmicro"
			(at 334.01 248.92 0)
			(effects
				(font
					(size 1.27 1.27)
					(thickness 0.15)
				)
				(justify left bottom)
				(hide yes)
			)
		)
		(property "License" "Apache-2.0"
			(at 334.01 251.46 0)
			(effects
				(font
					(size 1.27 1.27)
					(thickness 0.15)
				)
				(justify left bottom)
				(hide yes)
			)
		)
		(pin "1"
		)
		(instances
			(project "sdi-mipi-video-converter"
				(path ""
					(reference "#PWR058")
					(unit 1)
				)
			)
		)
	)
	(symbol
		(lib_id "antmicroPMICPowerDistributionSwitchesLoadDrivers:DIO7553ST6")
		(at 86.36 77.47 0)
		(unit 1)
		(exclude_from_sim no)
		(in_bom yes)
		(on_board yes)
		(dnp no)
		(fields_autoplaced yes)
		(property "Reference" "U4"
			(at 95.25 69.85 0)
			(effects
				(font
					(size 1.27 1.27)
					(thickness 0.15)
				)
			)
		)
		(property "Value" "DIO7553ST6"
			(at 95.25 72.39 0)
			(effects
				(font
					(size 1.27 1.27)
					(thickness 0.15)
				)
			)
		)
		(property "Footprint" "antmicro-footprints:SOT-23-6"
			(at 118.11 85.09 0)
			(effects
				(font
					(size 1.27 1.27)
					(thickness 0.15)
				)
				(justify left bottom)
				(hide yes)
			)
		)
		(property "Datasheet" "https://www.mouser.com/datasheet/2/802/7e5c577022fb784effcb3cdb25b437c0-1815562.pdf"
			(at 118.11 87.63 0)
			(effects
				(font
					(size 1.27 1.27)
					(thickness 0.15)
				)
				(justify left bottom)
				(hide yes)
			)
		)
		(property "Description" "Power switch"
			(at 86.36 77.47 0)
			(effects
				(font
					(size 1.27 1.27)
				)
				(hide yes)
			)
		)
		(property "MPN" "DIO7553ST6"
			(at 118.11 90.17 0)
			(effects
				(font
					(size 1.27 1.27)
					(thickness 0.15)
				)
				(justify left bottom)
				(hide yes)
			)
		)
		(property "Manufacturer" "DIOO Microcircuits"
			(at 118.11 92.71 0)
			(effects
				(font
					(size 1.27 1.27)
					(thickness 0.15)
				)
				(justify left bottom)
				(hide yes)
			)
		)
		(property "Author" "Antmicro"
			(at 118.11 95.25 0)
			(effects
				(font
					(size 1.27 1.27)
					(thickness 0.15)
				)
				(justify left bottom)
				(hide yes)
			)
		)
		(property "License" "Apache-2.0"
			(at 118.11 97.79 0)
			(effects
				(font
					(size 1.27 1.27)
					(thickness 0.15)
				)
				(justify left bottom)
				(hide yes)
			)
		)
		(pin "1"
		)
		(pin "2"
		)
		(pin "3"
		)
		(pin "4"
		)
		(pin "5"
		)
		(pin "6"
		)
		(instances
			(project "sdi-mipi-video-converter"
				(path ""
					(reference "U4")
					(unit 1)
				)
			)
		)
	)
	(symbol
		(lib_id "antmicroOperationalAmplifiers:LM339_TSSOP_CUSTOM_Split")
		(at 29.21 194.31 0)
		(unit 5)
		(exclude_from_sim no)
		(in_bom yes)
		(on_board yes)
		(dnp no)
		(fields_autoplaced yes)
		(property "Reference" "U2"
			(at 38.1 193.04 0)
			(effects
				(font
					(size 1.27 1.27)
					(thickness 0.15)
				)
				(justify left)
			)
		)
		(property "Value" "LM339_TSSOP_Split"
			(at 38.1 195.58 0)
			(effects
				(font
					(size 1.27 1.27)
					(thickness 0.15)
				)
				(justify left)
			)
		)
		(property "Footprint" "antmicro-footprints:TSSOP-14_4.4x5mm_P0.65mm"
			(at 54.61 204.47 0)
			(effects
				(font
					(size 1.27 1.27)
					(thickness 0.15)
				)
				(justify left bottom)
				(hide yes)
			)
		)
		(property "Datasheet" "https://www.ti.com/lit/ds/symlink/lm339b.pdf?ts=1679641364820&ref_url=https%253A%252F%252Fwww.google.com%252F"
			(at 54.61 207.01 0)
			(effects
				(font
					(size 1.27 1.27)
					(thickness 0.15)
				)
				(justify left bottom)
				(hide yes)
			)
		)
		(property "Description" "Analogue Comparator, Differential, 4 Comparators, 300 ns, 2V to 36V, TSSOP, 14 Pins"
			(at 54.61 219.71 0)
			(effects
				(font
					(size 1.27 1.27)
				)
				(justify left bottom)
				(hide yes)
			)
		)
		(property "MPN" "LM339PW"
			(at 38.1 198.12 0)
			(effects
				(font
					(size 1.27 1.27)
					(thickness 0.15)
				)
				(justify left)
			)
		)
		(property "Manufacturer" "Texas Instruments"
			(at 54.61 212.09 0)
			(effects
				(font
					(size 1.27 1.27)
					(thickness 0.15)
				)
				(justify left bottom)
				(hide yes)
			)
		)
		(property "Author" "Antmicro"
			(at 54.61 214.63 0)
			(effects
				(font
					(size 1.27 1.27)
					(thickness 0.15)
				)
				(justify left bottom)
				(hide yes)
			)
		)
		(property "License" "Apache-2.0"
			(at 54.61 217.17 0)
			(effects
				(font
					(size 1.27 1.27)
					(thickness 0.15)
				)
				(justify left bottom)
				(hide yes)
			)
		)
		(pin "2"
		)
		(pin "4"
		)
		(pin "5"
		)
		(pin "1"
		)
		(pin "6"
		)
		(pin "7"
		)
		(pin "14"
		)
		(pin "8"
		)
		(pin "9"
		)
		(pin "10"
		)
		(pin "11"
		)
		(pin "13"
		)
		(pin "12"
		)
		(pin "3"
		)
		(instances
			(project "sdi-mipi-video-converter"
				(path ""
					(reference "U2")
					(unit 5)
				)
			)
		)
	)
	(symbol
		(lib_id "antmicropower:+1V2")
		(at 240.03 187.96 0)
		(unit 1)
		(exclude_from_sim no)
		(in_bom yes)
		(on_board yes)
		(dnp no)
		(fields_autoplaced yes)
		(property "Reference" "#PWR041"
			(at 240.03 191.77 0)
			(effects
				(font
					(size 1.27 1.27)
				)
				(hide yes)
			)
		)
		(property "Value" "+1V2"
			(at 240.03 182.88 0)
			(effects
				(font
					(size 1.27 1.27)
				)
			)
		)
		(property "Footprint" ""
			(at 240.03 187.96 0)
			(effects
				(font
					(size 1.27 1.27)
				)
				(hide yes)
			)
		)
		(property "Datasheet" ""
			(at 240.03 187.96 0)
			(effects
				(font
					(size 1.27 1.27)
				)
				(hide yes)
			)
		)
		(property "Description" ""
			(at 240.03 187.96 0)
			(effects
				(font
					(size 1.27 1.27)
				)
				(hide yes)
			)
		)
		(pin "1"
		)
		(instances
			(project "sdi-mipi-video-converter"
				(path ""
					(reference "#PWR041")
					(unit 1)
				)
			)
		)
	)
	(symbol
		(lib_id "antmicroResistors0402:R_10k_0402")
		(at 86.36 60.96 270)
		(mirror x)
		(unit 1)
		(exclude_from_sim no)
		(in_bom yes)
		(on_board yes)
		(dnp no)
		(fields_autoplaced yes)
		(property "Reference" "R64"
			(at 83.82 57.1499 90)
			(effects
				(font
					(size 1.27 1.27)
					(thickness 0.15)
				)
				(justify right)
			)
		)
		(property "Value" "R_10k_0402"
			(at 73.66 40.64 0)
			(effects
				(font
					(size 1.27 1.27)
					(thickness 0.15)
				)
				(justify left bottom)
				(hide yes)
			)
		)
		(property "Footprint" "antmicro-footprints:R_0402_1005Metric"
			(at 71.12 40.64 0)
			(effects
				(font
					(size 1.27 1.27)
					(thickness 0.15)
				)
				(justify left bottom)
				(hide yes)
			)
		)
		(property "Datasheet" "https://www.bourns.com/docs/product-datasheets/cr.pdf"
			(at 68.58 40.64 0)
			(effects
				(font
					(size 1.27 1.27)
					(thickness 0.15)
				)
				(justify left bottom)
				(hide yes)
			)
		)
		(property "Description" "SMD Chip Resistor, 10 kohm, ± 1%, 62.5 mW, 0402 [1005 Metric], Thick Film, General Purpose"
			(at 86.36 60.96 0)
			(effects
				(font
					(size 1.27 1.27)
				)
				(hide yes)
			)
		)
		(property "Manufacturer" "Bourns"
			(at 63.5 40.64 0)
			(effects
				(font
					(size 1.27 1.27)
					(thickness 0.15)
				)
				(justify left bottom)
				(hide yes)
			)
		)
		(property "MPN" "CR0402-FX-1002GLF"
			(at 66.04 40.64 0)
			(effects
				(font
					(size 1.27 1.27)
					(thickness 0.15)
				)
				(justify left bottom)
				(hide yes)
			)
		)
		(property "Val" "10k"
			(at 83.82 59.6899 90)
			(effects
				(font
					(size 1.27 1.27)
					(thickness 0.15)
				)
				(justify right)
			)
		)
		(property "License" "Apache-2.0"
			(at 60.96 40.64 0)
			(effects
				(font
					(size 1.27 1.27)
					(thickness 0.15)
				)
				(justify left bottom)
				(hide yes)
			)
		)
		(property "Author" "Antmicro"
			(at 58.42 40.64 0)
			(effects
				(font
					(size 1.27 1.27)
					(thickness 0.15)
				)
				(justify left bottom)
				(hide yes)
			)
		)
		(property "Tolerance" "1%"
			(at 76.2 40.64 0)
			(effects
				(font
					(size 1.27 1.27)
				)
				(justify left bottom)
				(hide yes)
			)
		)
		(pin "1"
		)
		(pin "2"
		)
		(instances
			(project "sdi-mipi-video-converter"
				(path ""
					(reference "R64")
					(unit 1)
				)
			)
		)
	)
	(symbol
		(lib_id "antmicropower:GND")
		(at 86.36 62.23 0)
		(unit 1)
		(exclude_from_sim no)
		(in_bom yes)
		(on_board yes)
		(dnp no)
		(fields_autoplaced yes)
		(property "Reference" "#PWR0238"
			(at 95.25 64.77 0)
			(effects
				(font
					(size 1.27 1.27)
					(thickness 0.15)
				)
				(justify left bottom)
				(hide yes)
			)
		)
		(property "Value" "GND"
			(at 86.36 67.31 0)
			(effects
				(font
					(size 1.27 1.27)
					(thickness 0.15)
				)
			)
		)
		(property "Footprint" ""
			(at 95.25 69.85 0)
			(effects
				(font
					(size 1.27 1.27)
					(thickness 0.15)
				)
				(justify left bottom)
				(hide yes)
			)
		)
		(property "Datasheet" ""
			(at 95.25 74.93 0)
			(effects
				(font
					(size 1.27 1.27)
					(thickness 0.15)
				)
				(justify left bottom)
				(hide yes)
			)
		)
		(property "Description" ""
			(at 86.36 62.23 0)
			(effects
				(font
					(size 1.27 1.27)
				)
				(hide yes)
			)
		)
		(property "Author" "Antmicro"
			(at 95.25 69.85 0)
			(effects
				(font
					(size 1.27 1.27)
					(thickness 0.15)
				)
				(justify left bottom)
				(hide yes)
			)
		)
		(property "License" "Apache-2.0"
			(at 95.25 72.39 0)
			(effects
				(font
					(size 1.27 1.27)
					(thickness 0.15)
				)
				(justify left bottom)
				(hide yes)
			)
		)
		(pin "1"
		)
		(instances
			(project "sdi-mipi-video-converter"
				(path ""
					(reference "#PWR0238")
					(unit 1)
				)
			)
		)
	)
	(symbol
		(lib_id "antmicropower:GND")
		(at 377.19 58.42 0)
		(unit 1)
		(exclude_from_sim no)
		(in_bom yes)
		(on_board yes)
		(dnp no)
		(fields_autoplaced yes)
		(property "Reference" "#PWR070"
			(at 386.08 60.96 0)
			(effects
				(font
					(size 1.27 1.27)
					(thickness 0.15)
				)
				(justify left bottom)
				(hide yes)
			)
		)
		(property "Value" "GND"
			(at 377.19 63.5 0)
			(effects
				(font
					(size 1.27 1.27)
					(thickness 0.15)
				)
			)
		)
		(property "Footprint" ""
			(at 386.08 66.04 0)
			(effects
				(font
					(size 1.27 1.27)
					(thickness 0.15)
				)
				(justify left bottom)
				(hide yes)
			)
		)
		(property "Datasheet" ""
			(at 386.08 71.12 0)
			(effects
				(font
					(size 1.27 1.27)
					(thickness 0.15)
				)
				(justify left bottom)
				(hide yes)
			)
		)
		(property "Description" ""
			(at 377.19 58.42 0)
			(effects
				(font
					(size 1.27 1.27)
				)
				(hide yes)
			)
		)
		(property "Author" "Antmicro"
			(at 386.08 66.04 0)
			(effects
				(font
					(size 1.27 1.27)
					(thickness 0.15)
				)
				(justify left bottom)
				(hide yes)
			)
		)
		(property "License" "Apache-2.0"
			(at 386.08 68.58 0)
			(effects
				(font
					(size 1.27 1.27)
					(thickness 0.15)
				)
				(justify left bottom)
				(hide yes)
			)
		)
		(pin "1"
		)
		(instances
			(project "sdi-mipi-video-converter"
				(path ""
					(reference "#PWR070")
					(unit 1)
				)
			)
		)
	)
	(symbol
		(lib_id "antmicroCapacitors0402:C_100n_0402")
		(at 316.23 110.49 180)
		(unit 1)
		(exclude_from_sim no)
		(in_bom yes)
		(on_board yes)
		(dnp no)
		(fields_autoplaced yes)
		(property "Reference" "C14"
			(at 313.6836 115.57 0)
			(effects
				(font
					(size 1.27 1.27)
					(thickness 0.15)
				)
			)
		)
		(property "Value" "C_100n_0402"
			(at 295.91 100.33 0)
			(effects
				(font
					(size 1.27 1.27)
					(thickness 0.15)
				)
				(justify left bottom)
				(hide yes)
			)
		)
		(property "Footprint" "antmicro-footprints:C_0402_1005Metric"
			(at 295.91 97.79 0)
			(effects
				(font
					(size 1.27 1.27)
					(thickness 0.15)
				)
				(justify left bottom)
				(hide yes)
			)
		)
		(property "Datasheet" "https://www.murata.com/products/productdetail?partno=GRM155R61H104KE14%23"
			(at 295.91 95.25 0)
			(effects
				(font
					(size 1.27 1.27)
					(thickness 0.15)
				)
				(justify left bottom)
				(hide yes)
			)
		)
		(property "Description" "SMD Multilayer Ceramic Capacitor, 0.1 µF, 50 V, 0402 [1005 Metric], ± 10%, X5R, GRM Series"
			(at 316.23 110.49 0)
			(effects
				(font
					(size 1.27 1.27)
				)
				(hide yes)
			)
		)
		(property "Manufacturer" "Murata"
			(at 295.91 90.17 0)
			(effects
				(font
					(size 1.27 1.27)
					(thickness 0.15)
				)
				(justify left bottom)
				(hide yes)
			)
		)
		(property "MPN" "GRM155R61H104KE14D"
			(at 295.91 92.71 0)
			(effects
				(font
					(size 1.27 1.27)
					(thickness 0.15)
				)
				(justify left bottom)
				(hide yes)
			)
		)
		(property "Val" "100n"
			(at 313.6836 118.11 0)
			(effects
				(font
					(size 1.27 1.27)
					(thickness 0.15)
				)
			)
		)
		(property "License" "Apache-2.0"
			(at 295.91 87.63 0)
			(effects
				(font
					(size 1.27 1.27)
					(thickness 0.15)
				)
				(justify left bottom)
				(hide yes)
			)
		)
		(property "Author" "Antmicro"
			(at 295.91 85.09 0)
			(effects
				(font
					(size 1.27 1.27)
					(thickness 0.15)
				)
				(justify left bottom)
				(hide yes)
			)
		)
		(property "Voltage" "50V"
			(at 295.91 82.55 0)
			(effects
				(font
					(size 1.27 1.27)
				)
				(justify left bottom)
				(hide yes)
			)
		)
		(property "Dielectric" "X5R"
			(at 295.91 80.01 0)
			(effects
				(font
					(size 1.27 1.27)
				)
				(justify left bottom)
				(hide yes)
			)
		)
		(pin "1"
		)
		(pin "2"
		)
		(instances
			(project "sdi-mipi-video-converter"
				(path ""
					(reference "C14")
					(unit 1)
				)
			)
		)
	)
	(symbol
		(lib_id "antmicropower:GND")
		(at 388.62 58.42 0)
		(unit 1)
		(exclude_from_sim no)
		(in_bom yes)
		(on_board yes)
		(dnp no)
		(fields_autoplaced yes)
		(property "Reference" "#PWR078"
			(at 397.51 60.96 0)
			(effects
				(font
					(size 1.27 1.27)
					(thickness 0.15)
				)
				(justify left bottom)
				(hide yes)
			)
		)
		(property "Value" "GND"
			(at 388.62 63.5 0)
			(effects
				(font
					(size 1.27 1.27)
					(thickness 0.15)
				)
			)
		)
		(property "Footprint" ""
			(at 397.51 66.04 0)
			(effects
				(font
					(size 1.27 1.27)
					(thickness 0.15)
				)
				(justify left bottom)
				(hide yes)
			)
		)
		(property "Datasheet" ""
			(at 397.51 71.12 0)
			(effects
				(font
					(size 1.27 1.27)
					(thickness 0.15)
				)
				(justify left bottom)
				(hide yes)
			)
		)
		(property "Description" ""
			(at 388.62 58.42 0)
			(effects
				(font
					(size 1.27 1.27)
				)
				(hide yes)
			)
		)
		(property "Author" "Antmicro"
			(at 397.51 66.04 0)
			(effects
				(font
					(size 1.27 1.27)
					(thickness 0.15)
				)
				(justify left bottom)
				(hide yes)
			)
		)
		(property "License" "Apache-2.0"
			(at 397.51 68.58 0)
			(effects
				(font
					(size 1.27 1.27)
					(thickness 0.15)
				)
				(justify left bottom)
				(hide yes)
			)
		)
		(pin "1"
		)
		(instances
			(project "sdi-mipi-video-converter"
				(path ""
					(reference "#PWR078")
					(unit 1)
				)
			)
		)
	)
	(symbol
		(lib_id "antmicropower:GND")
		(at 325.12 171.45 0)
		(unit 1)
		(exclude_from_sim no)
		(in_bom yes)
		(on_board yes)
		(dnp no)
		(fields_autoplaced yes)
		(property "Reference" "#PWR056"
			(at 334.01 173.99 0)
			(effects
				(font
					(size 1.27 1.27)
					(thickness 0.15)
				)
				(justify left bottom)
				(hide yes)
			)
		)
		(property "Value" "GND"
			(at 325.12 176.53 0)
			(effects
				(font
					(size 1.27 1.27)
					(thickness 0.15)
				)
			)
		)
		(property "Footprint" ""
			(at 334.01 179.07 0)
			(effects
				(font
					(size 1.27 1.27)
					(thickness 0.15)
				)
				(justify left bottom)
				(hide yes)
			)
		)
		(property "Datasheet" ""
			(at 334.01 184.15 0)
			(effects
				(font
					(size 1.27 1.27)
					(thickness 0.15)
				)
				(justify left bottom)
				(hide yes)
			)
		)
		(property "Description" ""
			(at 325.12 171.45 0)
			(effects
				(font
					(size 1.27 1.27)
				)
				(hide yes)
			)
		)
		(property "Author" "Antmicro"
			(at 334.01 179.07 0)
			(effects
				(font
					(size 1.27 1.27)
					(thickness 0.15)
				)
				(justify left bottom)
				(hide yes)
			)
		)
		(property "License" "Apache-2.0"
			(at 334.01 181.61 0)
			(effects
				(font
					(size 1.27 1.27)
					(thickness 0.15)
				)
				(justify left bottom)
				(hide yes)
			)
		)
		(pin "1"
		)
		(instances
			(project "sdi-mipi-video-converter"
				(path ""
					(reference "#PWR056")
					(unit 1)
				)
			)
		)
	)
	(symbol
		(lib_id "antmicroResistors0402:R_0R_0402")
		(at 300.99 196.85 0)
		(unit 1)
		(exclude_from_sim no)
		(in_bom yes)
		(on_board yes)
		(dnp no)
		(fields_autoplaced yes)
		(property "Reference" "R20"
			(at 303.53 190.5 0)
			(effects
				(font
					(size 1.27 1.27)
					(thickness 0.15)
				)
			)
		)
		(property "Value" "R_0R_0402"
			(at 321.31 209.55 0)
			(effects
				(font
					(size 1.27 1.27)
					(thickness 0.15)
				)
				(justify left bottom)
				(hide yes)
			)
		)
		(property "Footprint" "antmicro-footprints:R_0402_1005Metric"
			(at 321.31 212.09 0)
			(effects
				(font
					(size 1.27 1.27)
					(thickness 0.15)
				)
				(justify left bottom)
				(hide yes)
			)
		)
		(property "Datasheet" "https://industrial.panasonic.com/cdbs/www-data/pdf/RDA0000/AOA0000C301.pdf"
			(at 321.31 214.63 0)
			(effects
				(font
					(size 1.27 1.27)
					(thickness 0.15)
				)
				(justify left bottom)
				(hide yes)
			)
		)
		(property "Description" "SMD Chip Resistor, Jumper, 0 ohm, 100 mW, 0402 [1005 Metric], Thick Film, General Purpose"
			(at 300.99 196.85 0)
			(effects
				(font
					(size 1.27 1.27)
				)
				(hide yes)
			)
		)
		(property "Manufacturer" "Panasonic"
			(at 321.31 219.71 0)
			(effects
				(font
					(size 1.27 1.27)
					(thickness 0.15)
				)
				(justify left bottom)
				(hide yes)
			)
		)
		(property "MPN" "ERJ2GE0R00X"
			(at 321.31 217.17 0)
			(effects
				(font
					(size 1.27 1.27)
					(thickness 0.15)
				)
				(justify left bottom)
				(hide yes)
			)
		)
		(property "Val" "0R"
			(at 303.53 193.04 0)
			(effects
				(font
					(size 1.27 1.27)
					(thickness 0.15)
				)
			)
		)
		(property "License" "Apache-2.0"
			(at 321.31 222.25 0)
			(effects
				(font
					(size 1.27 1.27)
					(thickness 0.15)
				)
				(justify left bottom)
				(hide yes)
			)
		)
		(property "Author" "Antmicro"
			(at 321.31 224.79 0)
			(effects
				(font
					(size 1.27 1.27)
					(thickness 0.15)
				)
				(justify left bottom)
				(hide yes)
			)
		)
		(property "Tolerance" "~"
			(at 321.31 207.01 0)
			(effects
				(font
					(size 1.27 1.27)
				)
				(justify left bottom)
				(hide yes)
			)
		)
		(property "Current" "1A"
			(at 321.31 227.33 0)
			(effects
				(font
					(size 1.27 1.27)
					(thickness 0.15)
				)
				(justify left bottom)
				(hide yes)
			)
		)
		(pin "1"
		)
		(pin "2"
		)
		(instances
			(project "sdi-mipi-video-converter"
				(path ""
					(reference "R20")
					(unit 1)
				)
			)
		)
	)
	(symbol
		(lib_id "antmicropower:GND")
		(at 53.34 156.21 0)
		(unit 1)
		(exclude_from_sim no)
		(in_bom yes)
		(on_board yes)
		(dnp no)
		(fields_autoplaced yes)
		(property "Reference" "#PWR0236"
			(at 62.23 158.75 0)
			(effects
				(font
					(size 1.27 1.27)
					(thickness 0.15)
				)
				(justify left bottom)
				(hide yes)
			)
		)
		(property "Value" "GND"
			(at 53.34 161.29 0)
			(effects
				(font
					(size 1.27 1.27)
					(thickness 0.15)
				)
			)
		)
		(property "Footprint" ""
			(at 62.23 163.83 0)
			(effects
				(font
					(size 1.27 1.27)
					(thickness 0.15)
				)
				(justify left bottom)
				(hide yes)
			)
		)
		(property "Datasheet" ""
			(at 62.23 168.91 0)
			(effects
				(font
					(size 1.27 1.27)
					(thickness 0.15)
				)
				(justify left bottom)
				(hide yes)
			)
		)
		(property "Description" ""
			(at 53.34 156.21 0)
			(effects
				(font
					(size 1.27 1.27)
				)
				(hide yes)
			)
		)
		(property "Author" "Antmicro"
			(at 62.23 163.83 0)
			(effects
				(font
					(size 1.27 1.27)
					(thickness 0.15)
				)
				(justify left bottom)
				(hide yes)
			)
		)
		(property "License" "Apache-2.0"
			(at 62.23 166.37 0)
			(effects
				(font
					(size 1.27 1.27)
					(thickness 0.15)
				)
				(justify left bottom)
				(hide yes)
			)
		)
		(pin "1"
		)
		(instances
			(project "sdi-mipi-video-converter"
				(path ""
					(reference "#PWR0236")
					(unit 1)
				)
			)
		)
	)
	(symbol
		(lib_id "antmicropower:GND")
		(at 247.65 194.31 0)
		(unit 1)
		(exclude_from_sim no)
		(in_bom yes)
		(on_board yes)
		(dnp no)
		(fields_autoplaced yes)
		(property "Reference" "#PWR043"
			(at 256.54 196.85 0)
			(effects
				(font
					(size 1.27 1.27)
					(thickness 0.15)
				)
				(justify left bottom)
				(hide yes)
			)
		)
		(property "Value" "GND"
			(at 247.65 199.39 0)
			(effects
				(font
					(size 1.27 1.27)
					(thickness 0.15)
				)
			)
		)
		(property "Footprint" ""
			(at 256.54 201.93 0)
			(effects
				(font
					(size 1.27 1.27)
					(thickness 0.15)
				)
				(justify left bottom)
				(hide yes)
			)
		)
		(property "Datasheet" ""
			(at 256.54 207.01 0)
			(effects
				(font
					(size 1.27 1.27)
					(thickness 0.15)
				)
				(justify left bottom)
				(hide yes)
			)
		)
		(property "Description" ""
			(at 247.65 194.31 0)
			(effects
				(font
					(size 1.27 1.27)
				)
				(hide yes)
			)
		)
		(property "Author" "Antmicro"
			(at 256.54 201.93 0)
			(effects
				(font
					(size 1.27 1.27)
					(thickness 0.15)
				)
				(justify left bottom)
				(hide yes)
			)
		)
		(property "License" "Apache-2.0"
			(at 256.54 204.47 0)
			(effects
				(font
					(size 1.27 1.27)
					(thickness 0.15)
				)
				(justify left bottom)
				(hide yes)
			)
		)
		(pin "1"
		)
		(instances
			(project "sdi-mipi-video-converter"
				(path ""
					(reference "#PWR043")
					(unit 1)
				)
			)
		)
	)
	(symbol
		(lib_id "antmicropower:GND")
		(at 195.58 194.31 0)
		(unit 1)
		(exclude_from_sim no)
		(in_bom yes)
		(on_board yes)
		(dnp no)
		(fields_autoplaced yes)
		(property "Reference" "#PWR028"
			(at 204.47 196.85 0)
			(effects
				(font
					(size 1.27 1.27)
					(thickness 0.15)
				)
				(justify left bottom)
				(hide yes)
			)
		)
		(property "Value" "GND"
			(at 195.58 199.39 0)
			(effects
				(font
					(size 1.27 1.27)
					(thickness 0.15)
				)
			)
		)
		(property "Footprint" ""
			(at 204.47 201.93 0)
			(effects
				(font
					(size 1.27 1.27)
					(thickness 0.15)
				)
				(justify left bottom)
				(hide yes)
			)
		)
		(property "Datasheet" ""
			(at 204.47 207.01 0)
			(effects
				(font
					(size 1.27 1.27)
					(thickness 0.15)
				)
				(justify left bottom)
				(hide yes)
			)
		)
		(property "Description" ""
			(at 195.58 194.31 0)
			(effects
				(font
					(size 1.27 1.27)
				)
				(hide yes)
			)
		)
		(property "Author" "Antmicro"
			(at 204.47 201.93 0)
			(effects
				(font
					(size 1.27 1.27)
					(thickness 0.15)
				)
				(justify left bottom)
				(hide yes)
			)
		)
		(property "License" "Apache-2.0"
			(at 204.47 204.47 0)
			(effects
				(font
					(size 1.27 1.27)
					(thickness 0.15)
				)
				(justify left bottom)
				(hide yes)
			)
		)
		(pin "1"
		)
		(instances
			(project "sdi-mipi-video-converter"
				(path ""
					(reference "#PWR028")
					(unit 1)
				)
			)
		)
	)
	(symbol
		(lib_id "antmicropower:GND")
		(at 336.55 91.44 0)
		(unit 1)
		(exclude_from_sim no)
		(in_bom yes)
		(on_board yes)
		(dnp no)
		(fields_autoplaced yes)
		(property "Reference" "#PWR053"
			(at 345.44 93.98 0)
			(effects
				(font
					(size 1.27 1.27)
					(thickness 0.15)
				)
				(justify left bottom)
				(hide yes)
			)
		)
		(property "Value" "GND"
			(at 336.55 96.52 0)
			(effects
				(font
					(size 1.27 1.27)
					(thickness 0.15)
				)
			)
		)
		(property "Footprint" ""
			(at 345.44 99.06 0)
			(effects
				(font
					(size 1.27 1.27)
					(thickness 0.15)
				)
				(justify left bottom)
				(hide yes)
			)
		)
		(property "Datasheet" ""
			(at 345.44 104.14 0)
			(effects
				(font
					(size 1.27 1.27)
					(thickness 0.15)
				)
				(justify left bottom)
				(hide yes)
			)
		)
		(property "Description" ""
			(at 336.55 91.44 0)
			(effects
				(font
					(size 1.27 1.27)
				)
				(hide yes)
			)
		)
		(property "Author" "Antmicro"
			(at 345.44 99.06 0)
			(effects
				(font
					(size 1.27 1.27)
					(thickness 0.15)
				)
				(justify left bottom)
				(hide yes)
			)
		)
		(property "License" "Apache-2.0"
			(at 345.44 101.6 0)
			(effects
				(font
					(size 1.27 1.27)
					(thickness 0.15)
				)
				(justify left bottom)
				(hide yes)
			)
		)
		(pin "1"
		)
		(instances
			(project "sdi-mipi-video-converter"
				(path ""
					(reference "#PWR053")
					(unit 1)
				)
			)
		)
	)
	(symbol
		(lib_id "antmicroResistors0402:R_10k_0402")
		(at 73.66 85.09 90)
		(unit 1)
		(exclude_from_sim no)
		(in_bom yes)
		(on_board yes)
		(dnp no)
		(fields_autoplaced yes)
		(property "Reference" "R63"
			(at 76.2 81.2799 90)
			(effects
				(font
					(size 1.27 1.27)
					(thickness 0.15)
				)
				(justify right)
			)
		)
		(property "Value" "R_10k_0402"
			(at 86.36 64.77 0)
			(effects
				(font
					(size 1.27 1.27)
					(thickness 0.15)
				)
				(justify left bottom)
				(hide yes)
			)
		)
		(property "Footprint" "antmicro-footprints:R_0402_1005Metric"
			(at 88.9 64.77 0)
			(effects
				(font
					(size 1.27 1.27)
					(thickness 0.15)
				)
				(justify left bottom)
				(hide yes)
			)
		)
		(property "Datasheet" "https://www.bourns.com/docs/product-datasheets/cr.pdf"
			(at 91.44 64.77 0)
			(effects
				(font
					(size 1.27 1.27)
					(thickness 0.15)
				)
				(justify left bottom)
				(hide yes)
			)
		)
		(property "Description" "SMD Chip Resistor, 10 kohm, ± 1%, 62.5 mW, 0402 [1005 Metric], Thick Film, General Purpose"
			(at 73.66 85.09 0)
			(effects
				(font
					(size 1.27 1.27)
				)
				(hide yes)
			)
		)
		(property "Manufacturer" "Bourns"
			(at 96.52 64.77 0)
			(effects
				(font
					(size 1.27 1.27)
					(thickness 0.15)
				)
				(justify left bottom)
				(hide yes)
			)
		)
		(property "MPN" "CR0402-FX-1002GLF"
			(at 93.98 64.77 0)
			(effects
				(font
					(size 1.27 1.27)
					(thickness 0.15)
				)
				(justify left bottom)
				(hide yes)
			)
		)
		(property "Val" "10k"
			(at 76.2 83.8199 90)
			(effects
				(font
					(size 1.27 1.27)
					(thickness 0.15)
				)
				(justify right)
			)
		)
		(property "License" "Apache-2.0"
			(at 99.06 64.77 0)
			(effects
				(font
					(size 1.27 1.27)
					(thickness 0.15)
				)
				(justify left bottom)
				(hide yes)
			)
		)
		(property "Author" "Antmicro"
			(at 101.6 64.77 0)
			(effects
				(font
					(size 1.27 1.27)
					(thickness 0.15)
				)
				(justify left bottom)
				(hide yes)
			)
		)
		(property "Tolerance" "1%"
			(at 83.82 64.77 0)
			(effects
				(font
					(size 1.27 1.27)
				)
				(justify left bottom)
				(hide yes)
			)
		)
		(pin "1"
		)
		(pin "2"
		)
		(instances
			(project "sdi-mipi-video-converter"
				(path ""
					(reference "R63")
					(unit 1)
				)
			)
		)
	)
	(symbol
		(lib_id "antmicroResistors0402:R_0R_0402")
		(at 311.15 236.22 0)
		(unit 1)
		(exclude_from_sim no)
		(in_bom yes)
		(on_board yes)
		(dnp no)
		(fields_autoplaced yes)
		(property "Reference" "R28"
			(at 313.69 240.03 0)
			(effects
				(font
					(size 1.27 1.27)
					(thickness 0.15)
				)
			)
		)
		(property "Value" "R_0R_0402"
			(at 331.47 248.92 0)
			(effects
				(font
					(size 1.27 1.27)
					(thickness 0.15)
				)
				(justify left bottom)
				(hide yes)
			)
		)
		(property "Footprint" "antmicro-footprints:R_0402_1005Metric"
			(at 331.47 251.46 0)
			(effects
				(font
					(size 1.27 1.27)
					(thickness 0.15)
				)
				(justify left bottom)
				(hide yes)
			)
		)
		(property "Datasheet" "https://industrial.panasonic.com/cdbs/www-data/pdf/RDA0000/AOA0000C301.pdf"
			(at 331.47 254 0)
			(effects
				(font
					(size 1.27 1.27)
					(thickness 0.15)
				)
				(justify left bottom)
				(hide yes)
			)
		)
		(property "Description" "SMD Chip Resistor, Jumper, 0 ohm, 100 mW, 0402 [1005 Metric], Thick Film, General Purpose"
			(at 311.15 236.22 0)
			(effects
				(font
					(size 1.27 1.27)
				)
				(hide yes)
			)
		)
		(property "Manufacturer" "Panasonic"
			(at 331.47 259.08 0)
			(effects
				(font
					(size 1.27 1.27)
					(thickness 0.15)
				)
				(justify left bottom)
				(hide yes)
			)
		)
		(property "MPN" "ERJ2GE0R00X"
			(at 331.47 256.54 0)
			(effects
				(font
					(size 1.27 1.27)
					(thickness 0.15)
				)
				(justify left bottom)
				(hide yes)
			)
		)
		(property "Val" "0R"
			(at 313.69 242.57 0)
			(effects
				(font
					(size 1.27 1.27)
					(thickness 0.15)
				)
			)
		)
		(property "License" "Apache-2.0"
			(at 331.47 261.62 0)
			(effects
				(font
					(size 1.27 1.27)
					(thickness 0.15)
				)
				(justify left bottom)
				(hide yes)
			)
		)
		(property "Author" "Antmicro"
			(at 331.47 264.16 0)
			(effects
				(font
					(size 1.27 1.27)
					(thickness 0.15)
				)
				(justify left bottom)
				(hide yes)
			)
		)
		(property "Tolerance" "~"
			(at 331.47 246.38 0)
			(effects
				(font
					(size 1.27 1.27)
				)
				(justify left bottom)
				(hide yes)
			)
		)
		(property "Current" "1A"
			(at 331.47 266.7 0)
			(effects
				(font
					(size 1.27 1.27)
					(thickness 0.15)
				)
				(justify left bottom)
				(hide yes)
			)
		)
		(pin "1"
		)
		(pin "2"
		)
		(instances
			(project "sdi-mipi-video-converter"
				(path ""
					(reference "R28")
					(unit 1)
				)
			)
		)
	)
	(symbol
		(lib_id "antmicroOperationalAmplifiers:LM339_TSSOP_CUSTOM_Split")
		(at 120.65 231.14 0)
		(unit 2)
		(exclude_from_sim no)
		(in_bom yes)
		(on_board yes)
		(dnp no)
		(fields_autoplaced yes)
		(property "Reference" "U2"
			(at 125.73 224.79 0)
			(effects
				(font
					(size 1.27 1.27)
					(thickness 0.15)
				)
			)
		)
		(property "Value" "LM339_TSSOP_Split"
			(at 125.73 224.79 0)
			(effects
				(font
					(size 1.27 1.27)
					(thickness 0.15)
				)
				(hide yes)
			)
		)
		(property "Footprint" "antmicro-footprints:TSSOP-14_4.4x5mm_P0.65mm"
			(at 146.05 241.3 0)
			(effects
				(font
					(size 1.27 1.27)
					(thickness 0.15)
				)
				(justify left bottom)
				(hide yes)
			)
		)
		(property "Datasheet" "https://www.ti.com/lit/ds/symlink/lm339b.pdf?ts=1679641364820&ref_url=https%253A%252F%252Fwww.google.com%252F"
			(at 146.05 243.84 0)
			(effects
				(font
					(size 1.27 1.27)
					(thickness 0.15)
				)
				(justify left bottom)
				(hide yes)
			)
		)
		(property "Description" "Analogue Comparator, Differential, 4 Comparators, 300 ns, 2V to 36V, TSSOP, 14 Pins"
			(at 146.05 256.54 0)
			(effects
				(font
					(size 1.27 1.27)
				)
				(justify left bottom)
				(hide yes)
			)
		)
		(property "MPN" "LM339PW"
			(at 125.73 227.33 0)
			(effects
				(font
					(size 1.27 1.27)
					(thickness 0.15)
				)
			)
		)
		(property "Manufacturer" "Texas Instruments"
			(at 146.05 248.92 0)
			(effects
				(font
					(size 1.27 1.27)
					(thickness 0.15)
				)
				(justify left bottom)
				(hide yes)
			)
		)
		(property "Author" "Antmicro"
			(at 146.05 251.46 0)
			(effects
				(font
					(size 1.27 1.27)
					(thickness 0.15)
				)
				(justify left bottom)
				(hide yes)
			)
		)
		(property "License" "Apache-2.0"
			(at 146.05 254 0)
			(effects
				(font
					(size 1.27 1.27)
					(thickness 0.15)
				)
				(justify left bottom)
				(hide yes)
			)
		)
		(pin "2"
		)
		(pin "4"
		)
		(pin "5"
		)
		(pin "1"
		)
		(pin "6"
		)
		(pin "7"
		)
		(pin "14"
		)
		(pin "8"
		)
		(pin "9"
		)
		(pin "10"
		)
		(pin "11"
		)
		(pin "13"
		)
		(pin "12"
		)
		(pin "3"
		)
		(instances
			(project "sdi-mipi-video-converter"
				(path ""
					(reference "U2")
					(unit 2)
				)
			)
		)
	)
	(symbol
		(lib_id "antmicroResistors0603:R_0R_0603")
		(at 349.25 226.06 0)
		(unit 1)
		(exclude_from_sim no)
		(in_bom yes)
		(on_board yes)
		(dnp no)
		(fields_autoplaced yes)
		(property "Reference" "R37"
			(at 351.79 229.87 0)
			(effects
				(font
					(size 1.27 1.27)
					(thickness 0.15)
				)
			)
		)
		(property "Value" "R_0R_0603"
			(at 369.57 238.76 0)
			(effects
				(font
					(size 1.27 1.27)
					(thickness 0.15)
				)
				(justify left bottom)
				(hide yes)
			)
		)
		(property "Footprint" "antmicro-footprints:R_0603_1608Metric"
			(at 369.57 241.3 0)
			(effects
				(font
					(size 1.27 1.27)
					(thickness 0.15)
				)
				(justify left bottom)
				(hide yes)
			)
		)
		(property "Datasheet" "https://www.bourns.com/docs/product-datasheets/cr.pdf?sfvrsn=574d41f6_14"
			(at 369.57 243.84 0)
			(effects
				(font
					(size 1.27 1.27)
					(thickness 0.15)
				)
				(justify left bottom)
				(hide yes)
			)
		)
		(property "Description" "Zero Ohm Resistor, Jumper, 0603 [1608 Metric], Thick Film, 100 mW, 1 A, Surface Mount Device, CR"
			(at 349.25 226.06 0)
			(effects
				(font
					(size 1.27 1.27)
				)
				(hide yes)
			)
		)
		(property "Manufacturer" "Bourns"
			(at 369.57 248.92 0)
			(effects
				(font
					(size 1.27 1.27)
					(thickness 0.15)
				)
				(justify left bottom)
				(hide yes)
			)
		)
		(property "MPN" "CR0603-J/-000ELF"
			(at 369.57 246.38 0)
			(effects
				(font
					(size 1.27 1.27)
					(thickness 0.15)
				)
				(justify left bottom)
				(hide yes)
			)
		)
		(property "Val" "0R"
			(at 351.79 232.41 0)
			(effects
				(font
					(size 1.27 1.27)
					(thickness 0.15)
				)
			)
		)
		(property "License" "Apache-2.0"
			(at 369.57 251.46 0)
			(effects
				(font
					(size 1.27 1.27)
					(thickness 0.15)
				)
				(justify left bottom)
				(hide yes)
			)
		)
		(property "Author" "Antmicro"
			(at 369.57 254 0)
			(effects
				(font
					(size 1.27 1.27)
					(thickness 0.15)
				)
				(justify left bottom)
				(hide yes)
			)
		)
		(property "Tolerance" "~"
			(at 369.57 236.22 0)
			(effects
				(font
					(size 1.27 1.27)
				)
				(justify left bottom)
				(hide yes)
			)
		)
		(property "Current" "1A"
			(at 369.57 256.54 0)
			(effects
				(font
					(size 1.27 1.27)
					(thickness 0.15)
				)
				(justify left bottom)
				(hide yes)
			)
		)
		(pin "1"
		)
		(pin "2"
		)
		(instances
			(project "sdi-mipi-video-converter"
				(path ""
					(reference "R37")
					(unit 1)
				)
			)
		)
	)
	(symbol
		(lib_id "antmicropower:GND")
		(at 345.44 210.82 0)
		(unit 1)
		(exclude_from_sim no)
		(in_bom yes)
		(on_board yes)
		(dnp no)
		(fields_autoplaced yes)
		(property "Reference" "#PWR066"
			(at 354.33 213.36 0)
			(effects
				(font
					(size 1.27 1.27)
					(thickness 0.15)
				)
				(justify left bottom)
				(hide yes)
			)
		)
		(property "Value" "GND"
			(at 345.44 215.9 0)
			(effects
				(font
					(size 1.27 1.27)
					(thickness 0.15)
				)
			)
		)
		(property "Footprint" ""
			(at 354.33 218.44 0)
			(effects
				(font
					(size 1.27 1.27)
					(thickness 0.15)
				)
				(justify left bottom)
				(hide yes)
			)
		)
		(property "Datasheet" ""
			(at 354.33 223.52 0)
			(effects
				(font
					(size 1.27 1.27)
					(thickness 0.15)
				)
				(justify left bottom)
				(hide yes)
			)
		)
		(property "Description" ""
			(at 345.44 210.82 0)
			(effects
				(font
					(size 1.27 1.27)
				)
				(hide yes)
			)
		)
		(property "Author" "Antmicro"
			(at 354.33 218.44 0)
			(effects
				(font
					(size 1.27 1.27)
					(thickness 0.15)
				)
				(justify left bottom)
				(hide yes)
			)
		)
		(property "License" "Apache-2.0"
			(at 354.33 220.98 0)
			(effects
				(font
					(size 1.27 1.27)
					(thickness 0.15)
				)
				(justify left bottom)
				(hide yes)
			)
		)
		(pin "1"
		)
		(instances
			(project "sdi-mipi-video-converter"
				(path ""
					(reference "#PWR066")
					(unit 1)
				)
			)
		)
	)
	(symbol
		(lib_id "antmicroCapacitors0603:C_22u_0603")
		(at 355.6 52.07 90)
		(unit 1)
		(exclude_from_sim no)
		(in_bom yes)
		(on_board yes)
		(dnp no)
		(fields_autoplaced yes)
		(property "Reference" "C22"
			(at 358.14 48.2535 90)
			(effects
				(font
					(size 1.27 1.27)
					(thickness 0.15)
				)
				(justify right)
			)
		)
		(property "Value" "C_22u_0603"
			(at 365.76 31.75 0)
			(effects
				(font
					(size 1.27 1.27)
					(thickness 0.15)
				)
				(justify left bottom)
				(hide yes)
			)
		)
		(property "Footprint" "antmicro-footprints:C_0603_1608Metric"
			(at 368.3 31.75 0)
			(effects
				(font
					(size 1.27 1.27)
					(thickness 0.15)
				)
				(justify left bottom)
				(hide yes)
			)
		)
		(property "Datasheet" "https://www.murata.com/products/productdetail?partno=GRM188R60J226MEA0%23"
			(at 370.84 31.75 0)
			(effects
				(font
					(size 1.27 1.27)
					(thickness 0.15)
				)
				(justify left bottom)
				(hide yes)
			)
		)
		(property "Description" "SMD Multilayer Ceramic Capacitor, 22 µF, 6.3 V, 0603 [1608 Metric], ± 20%, X5R, GRM Series"
			(at 355.6 52.07 0)
			(effects
				(font
					(size 1.27 1.27)
				)
				(hide yes)
			)
		)
		(property "Manufacturer" "Murata"
			(at 375.92 31.75 0)
			(effects
				(font
					(size 1.27 1.27)
					(thickness 0.15)
				)
				(justify left bottom)
				(hide yes)
			)
		)
		(property "MPN" "GRM188R60J226MEA0D"
			(at 373.38 31.75 0)
			(effects
				(font
					(size 1.27 1.27)
					(thickness 0.15)
				)
				(justify left bottom)
				(hide yes)
			)
		)
		(property "Val" "22u"
			(at 358.14 50.7935 90)
			(effects
				(font
					(size 1.27 1.27)
					(thickness 0.15)
				)
				(justify right)
			)
		)
		(property "License" "Apache-2.0"
			(at 378.46 31.75 0)
			(effects
				(font
					(size 1.27 1.27)
					(thickness 0.15)
				)
				(justify left bottom)
				(hide yes)
			)
		)
		(property "Author" "Antmicro"
			(at 381 31.75 0)
			(effects
				(font
					(size 1.27 1.27)
					(thickness 0.15)
				)
				(justify left bottom)
				(hide yes)
			)
		)
		(property "Voltage" ""
			(at 383.54 31.75 0)
			(effects
				(font
					(size 1.27 1.27)
				)
				(justify left bottom)
				(hide yes)
			)
		)
		(property "Dielectric" ""
			(at 386.08 31.75 0)
			(effects
				(font
					(size 1.27 1.27)
				)
				(justify left bottom)
				(hide yes)
			)
		)
		(pin "1"
		)
		(pin "2"
		)
		(instances
			(project "sdi-mipi-video-converter"
				(path ""
					(reference "C22")
					(unit 1)
				)
			)
		)
	)
	(symbol
		(lib_id "antmicropower:GND")
		(at 86.36 154.94 0)
		(unit 1)
		(exclude_from_sim no)
		(in_bom yes)
		(on_board yes)
		(dnp no)
		(fields_autoplaced yes)
		(property "Reference" "#PWR0225"
			(at 95.25 157.48 0)
			(effects
				(font
					(size 1.27 1.27)
					(thickness 0.15)
				)
				(justify left bottom)
				(hide yes)
			)
		)
		(property "Value" "GND"
			(at 86.36 160.02 0)
			(effects
				(font
					(size 1.27 1.27)
					(thickness 0.15)
				)
			)
		)
		(property "Footprint" ""
			(at 95.25 162.56 0)
			(effects
				(font
					(size 1.27 1.27)
					(thickness 0.15)
				)
				(justify left bottom)
				(hide yes)
			)
		)
		(property "Datasheet" ""
			(at 95.25 167.64 0)
			(effects
				(font
					(size 1.27 1.27)
					(thickness 0.15)
				)
				(justify left bottom)
				(hide yes)
			)
		)
		(property "Description" ""
			(at 86.36 154.94 0)
			(effects
				(font
					(size 1.27 1.27)
				)
				(hide yes)
			)
		)
		(property "Author" "Antmicro"
			(at 95.25 162.56 0)
			(effects
				(font
					(size 1.27 1.27)
					(thickness 0.15)
				)
				(justify left bottom)
				(hide yes)
			)
		)
		(property "License" "Apache-2.0"
			(at 95.25 165.1 0)
			(effects
				(font
					(size 1.27 1.27)
					(thickness 0.15)
				)
				(justify left bottom)
				(hide yes)
			)
		)
		(pin "1"
		)
		(instances
			(project "sdi-mipi-video-converter"
				(path ""
					(reference "#PWR0225")
					(unit 1)
				)
			)
		)
	)
	(symbol
		(lib_id "antmicroResistors0402:R_3k01_0402")
		(at 345.44 163.83 90)
		(unit 1)
		(exclude_from_sim no)
		(in_bom yes)
		(on_board yes)
		(dnp no)
		(fields_autoplaced yes)
		(property "Reference" "R31"
			(at 347.98 160.0199 90)
			(effects
				(font
					(size 1.27 1.27)
					(thickness 0.15)
				)
				(justify right)
			)
		)
		(property "Value" "R_3k01_0402"
			(at 358.14 143.51 0)
			(effects
				(font
					(size 1.27 1.27)
					(thickness 0.15)
				)
				(justify left bottom)
				(hide yes)
			)
		)
		(property "Footprint" "antmicro-footprints:R_0402_1005Metric"
			(at 360.68 143.51 0)
			(effects
				(font
					(size 1.27 1.27)
					(thickness 0.15)
				)
				(justify left bottom)
				(hide yes)
			)
		)
		(property "Datasheet" "https://www.bourns.com/docs/product-datasheets/cr.pdf"
			(at 363.22 143.51 0)
			(effects
				(font
					(size 1.27 1.27)
					(thickness 0.15)
				)
				(justify left bottom)
				(hide yes)
			)
		)
		(property "Description" "SMD Chip Resistor, 3.01 kohm, ± 1%, 62.5 mW, 0402 [1005 Metric], Thick Film, General Purpose"
			(at 345.44 163.83 0)
			(effects
				(font
					(size 1.27 1.27)
				)
				(hide yes)
			)
		)
		(property "Manufacturer" "Bourns"
			(at 368.3 143.51 0)
			(effects
				(font
					(size 1.27 1.27)
					(thickness 0.15)
				)
				(justify left bottom)
				(hide yes)
			)
		)
		(property "MPN" "CR0402-FX-3011GLF"
			(at 365.76 143.51 0)
			(effects
				(font
					(size 1.27 1.27)
					(thickness 0.15)
				)
				(justify left bottom)
				(hide yes)
			)
		)
		(property "Val" "3k01"
			(at 347.98 162.5599 90)
			(effects
				(font
					(size 1.27 1.27)
					(thickness 0.15)
				)
				(justify right)
			)
		)
		(property "License" "Apache-2.0"
			(at 370.84 143.51 0)
			(effects
				(font
					(size 1.27 1.27)
					(thickness 0.15)
				)
				(justify left bottom)
				(hide yes)
			)
		)
		(property "Author" "Antmicro"
			(at 373.38 143.51 0)
			(effects
				(font
					(size 1.27 1.27)
					(thickness 0.15)
				)
				(justify left bottom)
				(hide yes)
			)
		)
		(property "Tolerance" "1%"
			(at 355.6 143.51 0)
			(effects
				(font
					(size 1.27 1.27)
				)
				(justify left bottom)
				(hide yes)
			)
		)
		(pin "1"
		)
		(pin "2"
		)
		(instances
			(project "sdi-mipi-video-converter"
				(path ""
					(reference "R31")
					(unit 1)
				)
			)
		)
	)
	(symbol
		(lib_id "antmicroCapacitors0603:C_1u_0603")
		(at 38.1 88.9 90)
		(unit 1)
		(exclude_from_sim no)
		(in_bom yes)
		(on_board yes)
		(dnp no)
		(fields_autoplaced yes)
		(property "Reference" "C4"
			(at 40.64 85.0835 90)
			(effects
				(font
					(size 1.27 1.27)
					(thickness 0.15)
				)
				(justify right)
			)
		)
		(property "Value" "C_1u_0603"
			(at 48.26 68.58 0)
			(effects
				(font
					(size 1.27 1.27)
					(thickness 0.15)
				)
				(justify left bottom)
				(hide yes)
			)
		)
		(property "Footprint" "antmicro-footprints:C_0603_1608Metric"
			(at 50.8 68.58 0)
			(effects
				(font
					(size 1.27 1.27)
					(thickness 0.15)
				)
				(justify left bottom)
				(hide yes)
			)
		)
		(property "Datasheet" "https://spicat.kyocera-avx.com/product/mlcc/chartview/0603YD105KAT2A/"
			(at 53.34 68.58 0)
			(effects
				(font
					(size 1.27 1.27)
					(thickness 0.15)
				)
				(justify left bottom)
				(hide yes)
			)
		)
		(property "Description" "SMD Multilayer Ceramic Capacitor, 1 µF, 16 V, 0603 [1608 Metric], ± 10%, X5R, AVX 0603 MLCC"
			(at 38.1 88.9 0)
			(effects
				(font
					(size 1.27 1.27)
				)
				(hide yes)
			)
		)
		(property "Manufacturer" "KYOCERA AVX"
			(at 58.42 68.58 0)
			(effects
				(font
					(size 1.27 1.27)
					(thickness 0.15)
				)
				(justify left bottom)
				(hide yes)
			)
		)
		(property "MPN" "0603YD105KAT2A"
			(at 55.88 68.58 0)
			(effects
				(font
					(size 1.27 1.27)
					(thickness 0.15)
				)
				(justify left bottom)
				(hide yes)
			)
		)
		(property "Val" "1u"
			(at 40.64 87.6235 90)
			(effects
				(font
					(size 1.27 1.27)
					(thickness 0.15)
				)
				(justify right)
			)
		)
		(property "License" "Apache-2.0"
			(at 60.96 68.58 0)
			(effects
				(font
					(size 1.27 1.27)
					(thickness 0.15)
				)
				(justify left bottom)
				(hide yes)
			)
		)
		(property "Author" "Antmicro"
			(at 63.5 68.58 0)
			(effects
				(font
					(size 1.27 1.27)
					(thickness 0.15)
				)
				(justify left bottom)
				(hide yes)
			)
		)
		(property "Voltage" ""
			(at 66.04 68.58 0)
			(effects
				(font
					(size 1.27 1.27)
				)
				(justify left bottom)
				(hide yes)
			)
		)
		(property "Dielectric" ""
			(at 68.58 68.58 0)
			(effects
				(font
					(size 1.27 1.27)
				)
				(justify left bottom)
				(hide yes)
			)
		)
		(pin "1"
		)
		(pin "2"
		)
		(instances
			(project "sdi-mipi-video-converter"
				(path ""
					(reference "C4")
					(unit 1)
				)
			)
		)
	)
	(symbol
		(lib_id "antmicroResistors0402:R_0R_0402")
		(at 300.99 161.29 0)
		(unit 1)
		(exclude_from_sim no)
		(in_bom yes)
		(on_board yes)
		(dnp no)
		(fields_autoplaced yes)
		(property "Reference" "R19"
			(at 303.53 154.94 0)
			(effects
				(font
					(size 1.27 1.27)
					(thickness 0.15)
				)
			)
		)
		(property "Value" "R_0R_0402"
			(at 321.31 173.99 0)
			(effects
				(font
					(size 1.27 1.27)
					(thickness 0.15)
				)
				(justify left bottom)
				(hide yes)
			)
		)
		(property "Footprint" "antmicro-footprints:R_0402_1005Metric"
			(at 321.31 176.53 0)
			(effects
				(font
					(size 1.27 1.27)
					(thickness 0.15)
				)
				(justify left bottom)
				(hide yes)
			)
		)
		(property "Datasheet" "https://industrial.panasonic.com/cdbs/www-data/pdf/RDA0000/AOA0000C301.pdf"
			(at 321.31 179.07 0)
			(effects
				(font
					(size 1.27 1.27)
					(thickness 0.15)
				)
				(justify left bottom)
				(hide yes)
			)
		)
		(property "Description" "SMD Chip Resistor, Jumper, 0 ohm, 100 mW, 0402 [1005 Metric], Thick Film, General Purpose"
			(at 300.99 161.29 0)
			(effects
				(font
					(size 1.27 1.27)
				)
				(hide yes)
			)
		)
		(property "Manufacturer" "Panasonic"
			(at 321.31 184.15 0)
			(effects
				(font
					(size 1.27 1.27)
					(thickness 0.15)
				)
				(justify left bottom)
				(hide yes)
			)
		)
		(property "MPN" "ERJ2GE0R00X"
			(at 321.31 181.61 0)
			(effects
				(font
					(size 1.27 1.27)
					(thickness 0.15)
				)
				(justify left bottom)
				(hide yes)
			)
		)
		(property "Val" "0R"
			(at 303.53 157.48 0)
			(effects
				(font
					(size 1.27 1.27)
					(thickness 0.15)
				)
			)
		)
		(property "License" "Apache-2.0"
			(at 321.31 186.69 0)
			(effects
				(font
					(size 1.27 1.27)
					(thickness 0.15)
				)
				(justify left bottom)
				(hide yes)
			)
		)
		(property "Author" "Antmicro"
			(at 321.31 189.23 0)
			(effects
				(font
					(size 1.27 1.27)
					(thickness 0.15)
				)
				(justify left bottom)
				(hide yes)
			)
		)
		(property "Tolerance" "~"
			(at 321.31 171.45 0)
			(effects
				(font
					(size 1.27 1.27)
				)
				(justify left bottom)
				(hide yes)
			)
		)
		(property "Current" "1A"
			(at 321.31 191.77 0)
			(effects
				(font
					(size 1.27 1.27)
					(thickness 0.15)
				)
				(justify left bottom)
				(hide yes)
			)
		)
		(pin "1"
		)
		(pin "2"
		)
		(instances
			(project "sdi-mipi-video-converter"
				(path ""
					(reference "R19")
					(unit 1)
				)
			)
		)
	)
	(symbol
		(lib_id "antmicropower:+1V2")
		(at 359.41 190.5 0)
		(unit 1)
		(exclude_from_sim no)
		(in_bom yes)
		(on_board yes)
		(dnp no)
		(fields_autoplaced yes)
		(property "Reference" "#PWR072"
			(at 359.41 194.31 0)
			(effects
				(font
					(size 1.27 1.27)
				)
				(hide yes)
			)
		)
		(property "Value" "+1V2"
			(at 359.41 185.42 0)
			(effects
				(font
					(size 1.27 1.27)
				)
			)
		)
		(property "Footprint" ""
			(at 359.41 190.5 0)
			(effects
				(font
					(size 1.27 1.27)
				)
				(hide yes)
			)
		)
		(property "Datasheet" ""
			(at 359.41 190.5 0)
			(effects
				(font
					(size 1.27 1.27)
				)
				(hide yes)
			)
		)
		(property "Description" ""
			(at 359.41 190.5 0)
			(effects
				(font
					(size 1.27 1.27)
				)
				(hide yes)
			)
		)
		(pin "1"
		)
		(instances
			(project "sdi-mipi-video-converter"
				(path ""
					(reference "#PWR072")
					(unit 1)
				)
			)
		)
	)
	(symbol
		(lib_id "antmicroResistors0402:R_1k_0402")
		(at 101.6 204.47 90)
		(unit 1)
		(exclude_from_sim no)
		(in_bom yes)
		(on_board yes)
		(dnp no)
		(fields_autoplaced yes)
		(property "Reference" "R3"
			(at 104.14 200.6599 90)
			(effects
				(font
					(size 1.27 1.27)
					(thickness 0.15)
				)
				(justify right)
			)
		)
		(property "Value" "R_1k_0402"
			(at 114.3 184.15 0)
			(effects
				(font
					(size 1.27 1.27)
					(thickness 0.15)
				)
				(justify left bottom)
				(hide yes)
			)
		)
		(property "Footprint" "antmicro-footprints:R_0402_1005Metric"
			(at 116.84 184.15 0)
			(effects
				(font
					(size 1.27 1.27)
					(thickness 0.15)
				)
				(justify left bottom)
				(hide yes)
			)
		)
		(property "Datasheet" "https://www.bourns.com/docs/product-datasheets/cr.pdf"
			(at 119.38 184.15 0)
			(effects
				(font
					(size 1.27 1.27)
					(thickness 0.15)
				)
				(justify left bottom)
				(hide yes)
			)
		)
		(property "Description" "SMD Chip Resistor, 1 kohm, ± 1%, 63 mW, 0402 [1005 Metric], Thick Film, General Purpose"
			(at 101.6 204.47 0)
			(effects
				(font
					(size 1.27 1.27)
				)
				(hide yes)
			)
		)
		(property "Manufacturer" "Bourns"
			(at 124.46 184.15 0)
			(effects
				(font
					(size 1.27 1.27)
					(thickness 0.15)
				)
				(justify left bottom)
				(hide yes)
			)
		)
		(property "MPN" "CR0402-FX-1001GLF"
			(at 121.92 184.15 0)
			(effects
				(font
					(size 1.27 1.27)
					(thickness 0.15)
				)
				(justify left bottom)
				(hide yes)
			)
		)
		(property "Val" "1k"
			(at 104.14 203.1999 90)
			(effects
				(font
					(size 1.27 1.27)
					(thickness 0.15)
				)
				(justify right)
			)
		)
		(property "License" "Apache-2.0"
			(at 127 184.15 0)
			(effects
				(font
					(size 1.27 1.27)
					(thickness 0.15)
				)
				(justify left bottom)
				(hide yes)
			)
		)
		(property "Author" "Antmicro"
			(at 129.54 184.15 0)
			(effects
				(font
					(size 1.27 1.27)
					(thickness 0.15)
				)
				(justify left bottom)
				(hide yes)
			)
		)
		(property "Tolerance" "1%"
			(at 111.76 184.15 0)
			(effects
				(font
					(size 1.27 1.27)
				)
				(justify left bottom)
				(hide yes)
			)
		)
		(pin "1"
		)
		(pin "2"
		)
		(instances
			(project "sdi-mipi-video-converter"
				(path ""
					(reference "R3")
					(unit 1)
				)
			)
		)
	)
	(symbol
		(lib_id "antmicroCapacitors0603:C_10u_0603")
		(at 123.19 81.28 270)
		(unit 1)
		(exclude_from_sim no)
		(in_bom yes)
		(on_board yes)
		(dnp no)
		(fields_autoplaced yes)
		(property "Reference" "C10"
			(at 125.73 82.5562 90)
			(effects
				(font
					(size 1.27 1.27)
					(thickness 0.15)
				)
				(justify left)
			)
		)
		(property "Value" "C_10u_0603"
			(at 113.03 101.6 0)
			(effects
				(font
					(size 1.27 1.27)
					(thickness 0.15)
				)
				(justify left bottom)
				(hide yes)
			)
		)
		(property "Footprint" "antmicro-footprints:C_0603_1608Metric"
			(at 110.49 101.6 0)
			(effects
				(font
					(size 1.27 1.27)
					(thickness 0.15)
				)
				(justify left bottom)
				(hide yes)
			)
		)
		(property "Datasheet" "https://www.murata.com/products/productdetail?partno=GRM188R61A106KE69%23"
			(at 107.95 101.6 0)
			(effects
				(font
					(size 1.27 1.27)
					(thickness 0.15)
				)
				(justify left bottom)
				(hide yes)
			)
		)
		(property "Description" "SMD Multilayer Ceramic Capacitor, 10 µF, 10 V, 0603 [1608 Metric], ± 10%, X5R, GRM Series"
			(at 123.19 81.28 0)
			(effects
				(font
					(size 1.27 1.27)
				)
				(hide yes)
			)
		)
		(property "Manufacturer" "Murata"
			(at 102.87 101.6 0)
			(effects
				(font
					(size 1.27 1.27)
					(thickness 0.15)
				)
				(justify left bottom)
				(hide yes)
			)
		)
		(property "MPN" "GRM188R61A106KE69D"
			(at 105.41 101.6 0)
			(effects
				(font
					(size 1.27 1.27)
					(thickness 0.15)
				)
				(justify left bottom)
				(hide yes)
			)
		)
		(property "Val" "10u"
			(at 125.73 85.0962 90)
			(effects
				(font
					(size 1.27 1.27)
					(thickness 0.15)
				)
				(justify left)
			)
		)
		(property "License" "Apache-2.0"
			(at 100.33 101.6 0)
			(effects
				(font
					(size 1.27 1.27)
					(thickness 0.15)
				)
				(justify left bottom)
				(hide yes)
			)
		)
		(property "Author" "Antmicro"
			(at 97.79 101.6 0)
			(effects
				(font
					(size 1.27 1.27)
					(thickness 0.15)
				)
				(justify left bottom)
				(hide yes)
			)
		)
		(property "Voltage" ""
			(at 95.25 101.6 0)
			(effects
				(font
					(size 1.27 1.27)
				)
				(justify left bottom)
				(hide yes)
			)
		)
		(property "Dielectric" "template_dielectric"
			(at 92.71 101.6 0)
			(effects
				(font
					(size 1.27 1.27)
				)
				(justify left bottom)
				(hide yes)
			)
		)
		(pin "1"
		)
		(pin "2"
		)
		(instances
			(project "sdi-mipi-video-converter"
				(path ""
					(reference "C10")
					(unit 1)
				)
			)
		)
	)
	(symbol
		(lib_id "antmicroResistorsmisc:R_0R_0805")
		(at 394.97 105.41 0)
		(unit 1)
		(exclude_from_sim no)
		(in_bom yes)
		(on_board yes)
		(dnp no)
		(fields_autoplaced yes)
		(property "Reference" "R42"
			(at 397.51 99.06 0)
			(effects
				(font
					(size 1.27 1.27)
					(thickness 0.15)
				)
			)
		)
		(property "Value" "R_0R_0805"
			(at 415.29 118.11 0)
			(effects
				(font
					(size 1.27 1.27)
					(thickness 0.15)
				)
				(justify left bottom)
				(hide yes)
			)
		)
		(property "Footprint" "antmicro-footprints:R_0805_2012Metric"
			(at 415.29 120.65 0)
			(effects
				(font
					(size 1.27 1.27)
					(thickness 0.15)
				)
				(justify left bottom)
				(hide yes)
			)
		)
		(property "Datasheet" "https://www.vishay.com/docs/20035/dcrcwe3.pdf"
			(at 415.29 123.19 0)
			(effects
				(font
					(size 1.27 1.27)
					(thickness 0.15)
				)
				(justify left bottom)
				(hide yes)
			)
		)
		(property "Description" "Zero Ohm Resistor, Jumper, 0805 [2012 Metric], Thick Film, 125 mW, 2.5 A, Surface Mount Device"
			(at 394.97 105.41 0)
			(effects
				(font
					(size 1.27 1.27)
				)
				(hide yes)
			)
		)
		(property "Manufacturer" "Vishay"
			(at 415.29 128.27 0)
			(effects
				(font
					(size 1.27 1.27)
					(thickness 0.15)
				)
				(justify left bottom)
				(hide yes)
			)
		)
		(property "MPN" "CRCW08050000Z0EA"
			(at 415.29 125.73 0)
			(effects
				(font
					(size 1.27 1.27)
					(thickness 0.15)
				)
				(justify left bottom)
				(hide yes)
			)
		)
		(property "Val" "0R"
			(at 397.51 101.6 0)
			(effects
				(font
					(size 1.27 1.27)
					(thickness 0.15)
				)
			)
		)
		(property "License" "Apache-2.0"
			(at 415.29 130.81 0)
			(effects
				(font
					(size 1.27 1.27)
					(thickness 0.15)
				)
				(justify left bottom)
				(hide yes)
			)
		)
		(property "Author" "Antmicro"
			(at 415.29 133.35 0)
			(effects
				(font
					(size 1.27 1.27)
					(thickness 0.15)
				)
				(justify left bottom)
				(hide yes)
			)
		)
		(property "Tolerance" "~"
			(at 415.29 115.57 0)
			(effects
				(font
					(size 1.27 1.27)
				)
				(justify left bottom)
				(hide yes)
			)
		)
		(property "Current" "2.5A"
			(at 415.29 135.89 0)
			(effects
				(font
					(size 1.27 1.27)
					(thickness 0.15)
				)
				(justify left bottom)
				(hide yes)
			)
		)
		(pin "1"
		)
		(pin "2"
		)
		(instances
			(project "sdi-mipi-video-converter"
				(path ""
					(reference "R42")
					(unit 1)
				)
			)
		)
	)
	(symbol
		(lib_id "antmicropower:+1V8")
		(at 359.41 224.79 0)
		(unit 1)
		(exclude_from_sim no)
		(in_bom yes)
		(on_board yes)
		(dnp no)
		(fields_autoplaced yes)
		(property "Reference" "#PWR074"
			(at 374.65 227.33 0)
			(effects
				(font
					(size 1.27 1.27)
					(thickness 0.15)
				)
				(justify left bottom)
				(hide yes)
			)
		)
		(property "Value" "+1V8"
			(at 359.41 219.71 0)
			(effects
				(font
					(size 1.27 1.27)
					(thickness 0.15)
				)
			)
		)
		(property "Footprint" ""
			(at 374.65 232.41 0)
			(effects
				(font
					(size 1.27 1.27)
					(thickness 0.15)
				)
				(justify left bottom)
				(hide yes)
			)
		)
		(property "Datasheet" ""
			(at 374.65 234.95 0)
			(effects
				(font
					(size 1.27 1.27)
					(thickness 0.15)
				)
				(justify left bottom)
				(hide yes)
			)
		)
		(property "Description" ""
			(at 359.41 224.79 0)
			(effects
				(font
					(size 1.27 1.27)
				)
				(hide yes)
			)
		)
		(property "Author" "Antmicro"
			(at 374.65 232.41 0)
			(effects
				(font
					(size 1.27 1.27)
					(thickness 0.15)
				)
				(justify left bottom)
				(hide yes)
			)
		)
		(property "License" "Apache-2.0"
			(at 374.65 234.95 0)
			(effects
				(font
					(size 1.27 1.27)
					(thickness 0.15)
				)
				(justify left bottom)
				(hide yes)
			)
		)
		(pin "1"
		)
		(instances
			(project "sdi-mipi-video-converter"
				(path ""
					(reference "#PWR074")
					(unit 1)
				)
			)
		)
	)
	(symbol
		(lib_id "antmicroCapacitors0603:C_22u_0603")
		(at 377.19 52.07 90)
		(unit 1)
		(exclude_from_sim no)
		(in_bom yes)
		(on_board yes)
		(dnp no)
		(fields_autoplaced yes)
		(property "Reference" "C28"
			(at 379.73 48.2535 90)
			(effects
				(font
					(size 1.27 1.27)
					(thickness 0.15)
				)
				(justify right)
			)
		)
		(property "Value" "C_22u_0603"
			(at 387.35 31.75 0)
			(effects
				(font
					(size 1.27 1.27)
					(thickness 0.15)
				)
				(justify left bottom)
				(hide yes)
			)
		)
		(property "Footprint" "antmicro-footprints:C_0603_1608Metric"
			(at 389.89 31.75 0)
			(effects
				(font
					(size 1.27 1.27)
					(thickness 0.15)
				)
				(justify left bottom)
				(hide yes)
			)
		)
		(property "Datasheet" "https://www.murata.com/products/productdetail?partno=GRM188R60J226MEA0%23"
			(at 392.43 31.75 0)
			(effects
				(font
					(size 1.27 1.27)
					(thickness 0.15)
				)
				(justify left bottom)
				(hide yes)
			)
		)
		(property "Description" "SMD Multilayer Ceramic Capacitor, 22 µF, 6.3 V, 0603 [1608 Metric], ± 20%, X5R, GRM Series"
			(at 377.19 52.07 0)
			(effects
				(font
					(size 1.27 1.27)
				)
				(hide yes)
			)
		)
		(property "Manufacturer" "Murata"
			(at 397.51 31.75 0)
			(effects
				(font
					(size 1.27 1.27)
					(thickness 0.15)
				)
				(justify left bottom)
				(hide yes)
			)
		)
		(property "MPN" "GRM188R60J226MEA0D"
			(at 394.97 31.75 0)
			(effects
				(font
					(size 1.27 1.27)
					(thickness 0.15)
				)
				(justify left bottom)
				(hide yes)
			)
		)
		(property "Val" "22u"
			(at 379.73 50.7935 90)
			(effects
				(font
					(size 1.27 1.27)
					(thickness 0.15)
				)
				(justify right)
			)
		)
		(property "License" "Apache-2.0"
			(at 400.05 31.75 0)
			(effects
				(font
					(size 1.27 1.27)
					(thickness 0.15)
				)
				(justify left bottom)
				(hide yes)
			)
		)
		(property "Author" "Antmicro"
			(at 402.59 31.75 0)
			(effects
				(font
					(size 1.27 1.27)
					(thickness 0.15)
				)
				(justify left bottom)
				(hide yes)
			)
		)
		(property "Voltage" ""
			(at 405.13 31.75 0)
			(effects
				(font
					(size 1.27 1.27)
				)
				(justify left bottom)
				(hide yes)
			)
		)
		(property "Dielectric" ""
			(at 407.67 31.75 0)
			(effects
				(font
					(size 1.27 1.27)
				)
				(justify left bottom)
				(hide yes)
			)
		)
		(pin "1"
		)
		(pin "2"
		)
		(instances
			(project "sdi-mipi-video-converter"
				(path ""
					(reference "C28")
					(unit 1)
				)
			)
		)
	)
	(symbol
		(lib_id "antmicroResistors0402:R_10k_0402")
		(at 101.6 190.5 90)
		(unit 1)
		(exclude_from_sim no)
		(in_bom yes)
		(on_board yes)
		(dnp no)
		(fields_autoplaced yes)
		(property "Reference" "R2"
			(at 104.14 186.6899 90)
			(effects
				(font
					(size 1.27 1.27)
					(thickness 0.15)
				)
				(justify right)
			)
		)
		(property "Value" "R_10k_0402"
			(at 114.3 170.18 0)
			(effects
				(font
					(size 1.27 1.27)
					(thickness 0.15)
				)
				(justify left bottom)
				(hide yes)
			)
		)
		(property "Footprint" "antmicro-footprints:R_0402_1005Metric"
			(at 116.84 170.18 0)
			(effects
				(font
					(size 1.27 1.27)
					(thickness 0.15)
				)
				(justify left bottom)
				(hide yes)
			)
		)
		(property "Datasheet" "https://www.bourns.com/docs/product-datasheets/cr.pdf"
			(at 119.38 170.18 0)
			(effects
				(font
					(size 1.27 1.27)
					(thickness 0.15)
				)
				(justify left bottom)
				(hide yes)
			)
		)
		(property "Description" "SMD Chip Resistor, 10 kohm, ± 1%, 62.5 mW, 0402 [1005 Metric], Thick Film, General Purpose"
			(at 101.6 190.5 0)
			(effects
				(font
					(size 1.27 1.27)
				)
				(hide yes)
			)
		)
		(property "Manufacturer" "Bourns"
			(at 124.46 170.18 0)
			(effects
				(font
					(size 1.27 1.27)
					(thickness 0.15)
				)
				(justify left bottom)
				(hide yes)
			)
		)
		(property "MPN" "CR0402-FX-1002GLF"
			(at 121.92 170.18 0)
			(effects
				(font
					(size 1.27 1.27)
					(thickness 0.15)
				)
				(justify left bottom)
				(hide yes)
			)
		)
		(property "Val" "10k"
			(at 104.14 189.2299 90)
			(effects
				(font
					(size 1.27 1.27)
					(thickness 0.15)
				)
				(justify right)
			)
		)
		(property "License" "Apache-2.0"
			(at 127 170.18 0)
			(effects
				(font
					(size 1.27 1.27)
					(thickness 0.15)
				)
				(justify left bottom)
				(hide yes)
			)
		)
		(property "Author" "Antmicro"
			(at 129.54 170.18 0)
			(effects
				(font
					(size 1.27 1.27)
					(thickness 0.15)
				)
				(justify left bottom)
				(hide yes)
			)
		)
		(property "Tolerance" "1%"
			(at 111.76 170.18 0)
			(effects
				(font
					(size 1.27 1.27)
				)
				(justify left bottom)
				(hide yes)
			)
		)
		(pin "1"
		)
		(pin "2"
		)
		(instances
			(project "sdi-mipi-video-converter"
				(path ""
					(reference "R2")
					(unit 1)
				)
			)
		)
	)
	(symbol
		(lib_id "antmicroOperationalAmplifiers:LM339_TSSOP_CUSTOM_Split")
		(at 120.65 270.51 0)
		(unit 2)
		(exclude_from_sim no)
		(in_bom yes)
		(on_board yes)
		(dnp no)
		(fields_autoplaced yes)
		(property "Reference" "U3"
			(at 125.73 264.16 0)
			(effects
				(font
					(size 1.27 1.27)
					(thickness 0.15)
				)
			)
		)
		(property "Value" "LM339_TSSOP_Split"
			(at 125.73 264.16 0)
			(effects
				(font
					(size 1.27 1.27)
					(thickness 0.15)
				)
				(hide yes)
			)
		)
		(property "Footprint" "antmicro-footprints:TSSOP-14_4.4x5mm_P0.65mm"
			(at 146.05 280.67 0)
			(effects
				(font
					(size 1.27 1.27)
					(thickness 0.15)
				)
				(justify left bottom)
				(hide yes)
			)
		)
		(property "Datasheet" "https://www.ti.com/lit/ds/symlink/lm339b.pdf?ts=1679641364820&ref_url=https%253A%252F%252Fwww.google.com%252F"
			(at 146.05 283.21 0)
			(effects
				(font
					(size 1.27 1.27)
					(thickness 0.15)
				)
				(justify left bottom)
				(hide yes)
			)
		)
		(property "Description" "Analogue Comparator, Differential, 4 Comparators, 300 ns, 2V to 36V, TSSOP, 14 Pins"
			(at 146.05 295.91 0)
			(effects
				(font
					(size 1.27 1.27)
				)
				(justify left bottom)
				(hide yes)
			)
		)
		(property "MPN" "LM339PW"
			(at 125.73 266.7 0)
			(effects
				(font
					(size 1.27 1.27)
					(thickness 0.15)
				)
			)
		)
		(property "Manufacturer" "Texas Instruments"
			(at 146.05 288.29 0)
			(effects
				(font
					(size 1.27 1.27)
					(thickness 0.15)
				)
				(justify left bottom)
				(hide yes)
			)
		)
		(property "Author" "Antmicro"
			(at 146.05 290.83 0)
			(effects
				(font
					(size 1.27 1.27)
					(thickness 0.15)
				)
				(justify left bottom)
				(hide yes)
			)
		)
		(property "License" "Apache-2.0"
			(at 146.05 293.37 0)
			(effects
				(font
					(size 1.27 1.27)
					(thickness 0.15)
				)
				(justify left bottom)
				(hide yes)
			)
		)
		(pin "2"
		)
		(pin "4"
		)
		(pin "5"
		)
		(pin "1"
		)
		(pin "6"
		)
		(pin "7"
		)
		(pin "14"
		)
		(pin "8"
		)
		(pin "9"
		)
		(pin "10"
		)
		(pin "11"
		)
		(pin "13"
		)
		(pin "12"
		)
		(pin "3"
		)
		(instances
			(project "sdi-mipi-video-converter"
				(path ""
					(reference "U3")
					(unit 2)
				)
			)
		)
	)
	(symbol
		(lib_id "antmicroResistors0402:R_0R_0402")
		(at 300.99 231.14 0)
		(unit 1)
		(exclude_from_sim no)
		(in_bom yes)
		(on_board yes)
		(dnp no)
		(fields_autoplaced yes)
		(property "Reference" "R21"
			(at 303.53 224.79 0)
			(effects
				(font
					(size 1.27 1.27)
					(thickness 0.15)
				)
			)
		)
		(property "Value" "R_0R_0402"
			(at 321.31 243.84 0)
			(effects
				(font
					(size 1.27 1.27)
					(thickness 0.15)
				)
				(justify left bottom)
				(hide yes)
			)
		)
		(property "Footprint" "antmicro-footprints:R_0402_1005Metric"
			(at 321.31 246.38 0)
			(effects
				(font
					(size 1.27 1.27)
					(thickness 0.15)
				)
				(justify left bottom)
				(hide yes)
			)
		)
		(property "Datasheet" "https://industrial.panasonic.com/cdbs/www-data/pdf/RDA0000/AOA0000C301.pdf"
			(at 321.31 248.92 0)
			(effects
				(font
					(size 1.27 1.27)
					(thickness 0.15)
				)
				(justify left bottom)
				(hide yes)
			)
		)
		(property "Description" "SMD Chip Resistor, Jumper, 0 ohm, 100 mW, 0402 [1005 Metric], Thick Film, General Purpose"
			(at 300.99 231.14 0)
			(effects
				(font
					(size 1.27 1.27)
				)
				(hide yes)
			)
		)
		(property "Manufacturer" "Panasonic"
			(at 321.31 254 0)
			(effects
				(font
					(size 1.27 1.27)
					(thickness 0.15)
				)
				(justify left bottom)
				(hide yes)
			)
		)
		(property "MPN" "ERJ2GE0R00X"
			(at 321.31 251.46 0)
			(effects
				(font
					(size 1.27 1.27)
					(thickness 0.15)
				)
				(justify left bottom)
				(hide yes)
			)
		)
		(property "Val" "0R"
			(at 303.53 227.33 0)
			(effects
				(font
					(size 1.27 1.27)
					(thickness 0.15)
				)
			)
		)
		(property "License" "Apache-2.0"
			(at 321.31 256.54 0)
			(effects
				(font
					(size 1.27 1.27)
					(thickness 0.15)
				)
				(justify left bottom)
				(hide yes)
			)
		)
		(property "Author" "Antmicro"
			(at 321.31 259.08 0)
			(effects
				(font
					(size 1.27 1.27)
					(thickness 0.15)
				)
				(justify left bottom)
				(hide yes)
			)
		)
		(property "Tolerance" "~"
			(at 321.31 241.3 0)
			(effects
				(font
					(size 1.27 1.27)
				)
				(justify left bottom)
				(hide yes)
			)
		)
		(property "Current" "1A"
			(at 321.31 261.62 0)
			(effects
				(font
					(size 1.27 1.27)
					(thickness 0.15)
				)
				(justify left bottom)
				(hide yes)
			)
		)
		(pin "1"
		)
		(pin "2"
		)
		(instances
			(project "sdi-mipi-video-converter"
				(path ""
					(reference "R21")
					(unit 1)
				)
			)
		)
	)
	(symbol
		(lib_id "antmicroCapacitors0603:C_22u_0603")
		(at 109.22 142.24 90)
		(unit 1)
		(exclude_from_sim no)
		(in_bom yes)
		(on_board yes)
		(dnp no)
		(fields_autoplaced yes)
		(property "Reference" "C8"
			(at 111.76 138.4235 90)
			(effects
				(font
					(size 1.27 1.27)
					(thickness 0.15)
				)
				(justify right)
			)
		)
		(property "Value" "C_22u_0603"
			(at 119.38 121.92 0)
			(effects
				(font
					(size 1.27 1.27)
					(thickness 0.15)
				)
				(justify left bottom)
				(hide yes)
			)
		)
		(property "Footprint" "antmicro-footprints:C_0603_1608Metric"
			(at 121.92 121.92 0)
			(effects
				(font
					(size 1.27 1.27)
					(thickness 0.15)
				)
				(justify left bottom)
				(hide yes)
			)
		)
		(property "Datasheet" "https://www.murata.com/products/productdetail?partno=GRM188R60J226MEA0%23"
			(at 124.46 121.92 0)
			(effects
				(font
					(size 1.27 1.27)
					(thickness 0.15)
				)
				(justify left bottom)
				(hide yes)
			)
		)
		(property "Description" "SMD Multilayer Ceramic Capacitor, 22 µF, 6.3 V, 0603 [1608 Metric], ± 20%, X5R, GRM Series"
			(at 109.22 142.24 0)
			(effects
				(font
					(size 1.27 1.27)
				)
				(hide yes)
			)
		)
		(property "Manufacturer" "Murata"
			(at 129.54 121.92 0)
			(effects
				(font
					(size 1.27 1.27)
					(thickness 0.15)
				)
				(justify left bottom)
				(hide yes)
			)
		)
		(property "MPN" "GRM188R60J226MEA0D"
			(at 127 121.92 0)
			(effects
				(font
					(size 1.27 1.27)
					(thickness 0.15)
				)
				(justify left bottom)
				(hide yes)
			)
		)
		(property "Val" "22u"
			(at 111.76 140.9635 90)
			(effects
				(font
					(size 1.27 1.27)
					(thickness 0.15)
				)
				(justify right)
			)
		)
		(property "License" "Apache-2.0"
			(at 132.08 121.92 0)
			(effects
				(font
					(size 1.27 1.27)
					(thickness 0.15)
				)
				(justify left bottom)
				(hide yes)
			)
		)
		(property "Author" "Antmicro"
			(at 134.62 121.92 0)
			(effects
				(font
					(size 1.27 1.27)
					(thickness 0.15)
				)
				(justify left bottom)
				(hide yes)
			)
		)
		(property "Voltage" ""
			(at 137.16 121.92 0)
			(effects
				(font
					(size 1.27 1.27)
				)
				(justify left bottom)
				(hide yes)
			)
		)
		(property "Dielectric" ""
			(at 139.7 121.92 0)
			(effects
				(font
					(size 1.27 1.27)
				)
				(justify left bottom)
				(hide yes)
			)
		)
		(pin "1"
		)
		(pin "2"
		)
		(instances
			(project "sdi-mipi-video-converter"
				(path ""
					(reference "C8")
					(unit 1)
				)
			)
		)
	)
	(symbol
		(lib_id "antmicroCapacitors0603:C_1u_0603")
		(at 297.18 163.83 270)
		(unit 1)
		(exclude_from_sim no)
		(in_bom yes)
		(on_board yes)
		(dnp no)
		(fields_autoplaced yes)
		(property "Reference" "C17"
			(at 299.72 165.1062 90)
			(effects
				(font
					(size 1.27 1.27)
					(thickness 0.15)
				)
				(justify left)
			)
		)
		(property "Value" "C_1u_0603"
			(at 287.02 184.15 0)
			(effects
				(font
					(size 1.27 1.27)
					(thickness 0.15)
				)
				(justify left bottom)
				(hide yes)
			)
		)
		(property "Footprint" "antmicro-footprints:C_0603_1608Metric"
			(at 284.48 184.15 0)
			(effects
				(font
					(size 1.27 1.27)
					(thickness 0.15)
				)
				(justify left bottom)
				(hide yes)
			)
		)
		(property "Datasheet" "https://spicat.kyocera-avx.com/product/mlcc/chartview/0603YD105KAT2A/"
			(at 281.94 184.15 0)
			(effects
				(font
					(size 1.27 1.27)
					(thickness 0.15)
				)
				(justify left bottom)
				(hide yes)
			)
		)
		(property "Description" "SMD Multilayer Ceramic Capacitor, 1 µF, 16 V, 0603 [1608 Metric], ± 10%, X5R, AVX 0603 MLCC"
			(at 297.18 163.83 0)
			(effects
				(font
					(size 1.27 1.27)
				)
				(hide yes)
			)
		)
		(property "Manufacturer" "KYOCERA AVX"
			(at 276.86 184.15 0)
			(effects
				(font
					(size 1.27 1.27)
					(thickness 0.15)
				)
				(justify left bottom)
				(hide yes)
			)
		)
		(property "MPN" "0603YD105KAT2A"
			(at 279.4 184.15 0)
			(effects
				(font
					(size 1.27 1.27)
					(thickness 0.15)
				)
				(justify left bottom)
				(hide yes)
			)
		)
		(property "Val" "1u"
			(at 299.72 167.6462 90)
			(effects
				(font
					(size 1.27 1.27)
					(thickness 0.15)
				)
				(justify left)
			)
		)
		(property "License" "Apache-2.0"
			(at 274.32 184.15 0)
			(effects
				(font
					(size 1.27 1.27)
					(thickness 0.15)
				)
				(justify left bottom)
				(hide yes)
			)
		)
		(property "Author" "Antmicro"
			(at 271.78 184.15 0)
			(effects
				(font
					(size 1.27 1.27)
					(thickness 0.15)
				)
				(justify left bottom)
				(hide yes)
			)
		)
		(property "Voltage" ""
			(at 269.24 184.15 0)
			(effects
				(font
					(size 1.27 1.27)
				)
				(justify left bottom)
				(hide yes)
			)
		)
		(property "Dielectric" ""
			(at 266.7 184.15 0)
			(effects
				(font
					(size 1.27 1.27)
				)
				(justify left bottom)
				(hide yes)
			)
		)
		(pin "1"
		)
		(pin "2"
		)
		(instances
			(project "sdi-mipi-video-converter"
				(path ""
					(reference "C17")
					(unit 1)
				)
			)
		)
	)
	(symbol
		(lib_id "antmicroResistors0402:R_100k_0402")
		(at 60.96 146.05 180)
		(unit 1)
		(exclude_from_sim no)
		(in_bom yes)
		(on_board yes)
		(dnp no)
		(property "Reference" "R1"
			(at 58.42 142.24 0)
			(effects
				(font
					(size 1.27 1.27)
					(thickness 0.15)
				)
			)
		)
		(property "Value" "R_100k_0402"
			(at 40.64 133.35 0)
			(effects
				(font
					(size 1.27 1.27)
					(thickness 0.15)
				)
				(justify left bottom)
				(hide yes)
			)
		)
		(property "Footprint" "antmicro-footprints:R_0402_1005Metric"
			(at 40.64 130.81 0)
			(effects
				(font
					(size 1.27 1.27)
					(thickness 0.15)
				)
				(justify left bottom)
				(hide yes)
			)
		)
		(property "Datasheet" "https://www.bourns.com/docs/product-datasheets/cr.pdf"
			(at 40.64 128.27 0)
			(effects
				(font
					(size 1.27 1.27)
					(thickness 0.15)
				)
				(justify left bottom)
				(hide yes)
			)
		)
		(property "Description" "SMD Chip Resistor, 100 kohm, ± 1%, 62.5 mW, 0402 [1005 Metric], Thick Film, General Purpose"
			(at 60.96 146.05 0)
			(effects
				(font
					(size 1.27 1.27)
				)
				(hide yes)
			)
		)
		(property "Manufacturer" "Bourns"
			(at 40.64 123.19 0)
			(effects
				(font
					(size 1.27 1.27)
					(thickness 0.15)
				)
				(justify left bottom)
				(hide yes)
			)
		)
		(property "MPN" "CR0402-FX-1003GLF"
			(at 40.64 125.73 0)
			(effects
				(font
					(size 1.27 1.27)
					(thickness 0.15)
				)
				(justify left bottom)
				(hide yes)
			)
		)
		(property "Val" "100k"
			(at 58.42 144.145 0)
			(effects
				(font
					(size 1.27 1.27)
					(thickness 0.15)
				)
			)
		)
		(property "License" "Apache-2.0"
			(at 40.64 120.65 0)
			(effects
				(font
					(size 1.27 1.27)
					(thickness 0.15)
				)
				(justify left bottom)
				(hide yes)
			)
		)
		(property "Author" "Antmicro"
			(at 40.64 118.11 0)
			(effects
				(font
					(size 1.27 1.27)
					(thickness 0.15)
				)
				(justify left bottom)
				(hide yes)
			)
		)
		(property "Tolerance" "1%"
			(at 40.64 135.89 0)
			(effects
				(font
					(size 1.27 1.27)
				)
				(justify left bottom)
				(hide yes)
			)
		)
		(pin "1"
		)
		(pin "2"
		)
		(instances
			(project "sdi-mipi-video-converter"
				(path ""
					(reference "R1")
					(unit 1)
				)
			)
		)
	)
	(symbol
		(lib_id "antmicroPMICVoltageRegulatorsLinear:AP7330-W5-7")
		(at 317.5 196.85 0)
		(unit 1)
		(exclude_from_sim no)
		(in_bom yes)
		(on_board yes)
		(dnp no)
		(fields_autoplaced yes)
		(property "Reference" "U9"
			(at 325.12 190.5 0)
			(effects
				(font
					(size 1.27 1.27)
					(thickness 0.15)
				)
			)
		)
		(property "Value" "AP7330-W5-7"
			(at 325.12 193.04 0)
			(effects
				(font
					(size 1.27 1.27)
					(thickness 0.15)
				)
			)
		)
		(property "Footprint" "antmicro-footprints:SOT-23-5"
			(at 347.98 207.01 0)
			(effects
				(font
					(size 1.27 1.27)
					(thickness 0.15)
				)
				(justify left bottom)
				(hide yes)
			)
		)
		(property "Datasheet" "https://www.diodes.com/assets/Datasheets/AP7330.pdf"
			(at 347.98 209.55 0)
			(effects
				(font
					(size 1.27 1.27)
					(thickness 0.15)
				)
				(justify left bottom)
				(hide yes)
			)
		)
		(property "Description" "Voltage regulator"
			(at 317.5 196.85 0)
			(effects
				(font
					(size 1.27 1.27)
				)
				(hide yes)
			)
		)
		(property "MPN" "AP7330-W5-7"
			(at 347.98 212.09 0)
			(effects
				(font
					(size 1.27 1.27)
					(thickness 0.15)
				)
				(justify left bottom)
				(hide yes)
			)
		)
		(property "Manufacturer" "Diodes Incorporated"
			(at 347.98 214.63 0)
			(effects
				(font
					(size 1.27 1.27)
					(thickness 0.15)
				)
				(justify left bottom)
				(hide yes)
			)
		)
		(property "Author" "Antmicro"
			(at 347.98 217.17 0)
			(effects
				(font
					(size 1.27 1.27)
					(thickness 0.15)
				)
				(justify left bottom)
				(hide yes)
			)
		)
		(property "License" "Apache-2.0"
			(at 347.98 219.71 0)
			(effects
				(font
					(size 1.27 1.27)
					(thickness 0.15)
				)
				(justify left bottom)
				(hide yes)
			)
		)
		(pin "1"
		)
		(pin "2"
		)
		(pin "3"
		)
		(pin "4"
		)
		(pin "5"
		)
		(instances
			(project "sdi-mipi-video-converter"
				(path ""
					(reference "U9")
					(unit 1)
				)
			)
		)
	)
	(symbol
		(lib_id "antmicroCapacitors0603:C_22u_0603")
		(at 355.6 118.11 90)
		(unit 1)
		(exclude_from_sim no)
		(in_bom yes)
		(on_board yes)
		(dnp no)
		(fields_autoplaced yes)
		(property "Reference" "C21"
			(at 358.14 114.2935 90)
			(effects
				(font
					(size 1.27 1.27)
					(thickness 0.15)
				)
				(justify right)
			)
		)
		(property "Value" "C_22u_0603"
			(at 365.76 97.79 0)
			(effects
				(font
					(size 1.27 1.27)
					(thickness 0.15)
				)
				(justify left bottom)
				(hide yes)
			)
		)
		(property "Footprint" "antmicro-footprints:C_0603_1608Metric"
			(at 368.3 97.79 0)
			(effects
				(font
					(size 1.27 1.27)
					(thickness 0.15)
				)
				(justify left bottom)
				(hide yes)
			)
		)
		(property "Datasheet" "https://www.murata.com/products/productdetail?partno=GRM188R60J226MEA0%23"
			(at 370.84 97.79 0)
			(effects
				(font
					(size 1.27 1.27)
					(thickness 0.15)
				)
				(justify left bottom)
				(hide yes)
			)
		)
		(property "Description" "SMD Multilayer Ceramic Capacitor, 22 µF, 6.3 V, 0603 [1608 Metric], ± 20%, X5R, GRM Series"
			(at 355.6 118.11 0)
			(effects
				(font
					(size 1.27 1.27)
				)
				(hide yes)
			)
		)
		(property "Manufacturer" "Murata"
			(at 375.92 97.79 0)
			(effects
				(font
					(size 1.27 1.27)
					(thickness 0.15)
				)
				(justify left bottom)
				(hide yes)
			)
		)
		(property "MPN" "GRM188R60J226MEA0D"
			(at 373.38 97.79 0)
			(effects
				(font
					(size 1.27 1.27)
					(thickness 0.15)
				)
				(justify left bottom)
				(hide yes)
			)
		)
		(property "Val" "22u"
			(at 358.14 116.8335 90)
			(effects
				(font
					(size 1.27 1.27)
					(thickness 0.15)
				)
				(justify right)
			)
		)
		(property "License" "Apache-2.0"
			(at 378.46 97.79 0)
			(effects
				(font
					(size 1.27 1.27)
					(thickness 0.15)
				)
				(justify left bottom)
				(hide yes)
			)
		)
		(property "Author" "Antmicro"
			(at 381 97.79 0)
			(effects
				(font
					(size 1.27 1.27)
					(thickness 0.15)
				)
				(justify left bottom)
				(hide yes)
			)
		)
		(property "Voltage" ""
			(at 383.54 97.79 0)
			(effects
				(font
					(size 1.27 1.27)
				)
				(justify left bottom)
				(hide yes)
			)
		)
		(property "Dielectric" ""
			(at 386.08 97.79 0)
			(effects
				(font
					(size 1.27 1.27)
				)
				(justify left bottom)
				(hide yes)
			)
		)
		(pin "1"
		)
		(pin "2"
		)
		(instances
			(project "sdi-mipi-video-converter"
				(path ""
					(reference "C21")
					(unit 1)
				)
			)
		)
	)
	(symbol
		(lib_id "antmicroTestPoints:TP_0.75mm_SMD")
		(at 247.65 193.04 90)
		(unit 1)
		(exclude_from_sim no)
		(in_bom yes)
		(on_board yes)
		(dnp no)
		(fields_autoplaced yes)
		(property "Reference" "TP9"
			(at 250.19 189.8649 90)
			(effects
				(font
					(size 1.27 1.27)
					(thickness 0.15)
				)
				(justify right)
			)
		)
		(property "Value" "TP_0.75mm_SMD"
			(at 255.27 175.26 0)
			(effects
				(font
					(size 1.27 1.27)
					(thickness 0.15)
				)
				(justify left bottom)
				(hide yes)
			)
		)
		(property "Footprint" "antmicro-footprints:TP_SMD_0.75mm"
			(at 257.81 175.26 0)
			(effects
				(font
					(size 1.27 1.27)
					(thickness 0.15)
				)
				(justify left bottom)
				(hide yes)
			)
		)
		(property "Datasheet" ""
			(at 260.35 175.26 0)
			(effects
				(font
					(size 1.27 1.27)
					(thickness 0.15)
				)
				(justify left bottom)
				(hide yes)
			)
		)
		(property "Description" "SMT test point"
			(at 247.65 193.04 0)
			(effects
				(font
					(size 1.27 1.27)
				)
				(hide yes)
			)
		)
		(property "MPN" ""
			(at 262.89 175.26 0)
			(effects
				(font
					(size 1.27 1.27)
					(thickness 0.15)
				)
				(justify left bottom)
				(hide yes)
			)
		)
		(property "Manufacturer" ""
			(at 265.43 175.26 0)
			(effects
				(font
					(size 1.27 1.27)
					(thickness 0.15)
				)
				(justify left bottom)
				(hide yes)
			)
		)
		(property "Author" "Antmicro"
			(at 267.97 175.26 0)
			(effects
				(font
					(size 1.27 1.27)
					(thickness 0.15)
				)
				(justify left bottom)
				(hide yes)
			)
		)
		(property "License" "Apache-2.0"
			(at 270.51 175.26 0)
			(effects
				(font
					(size 1.27 1.27)
					(thickness 0.15)
				)
				(justify left bottom)
				(hide yes)
			)
		)
		(pin "1"
		)
		(instances
			(project "sdi-mipi-video-converter"
				(path ""
					(reference "TP9")
					(unit 1)
				)
			)
		)
	)
	(symbol
		(lib_id "antmicroCapacitors0603:C_22u_0603")
		(at 48.26 142.24 90)
		(unit 1)
		(exclude_from_sim no)
		(in_bom yes)
		(on_board yes)
		(dnp no)
		(property "Reference" "C5"
			(at 47.625 137.795 90)
			(effects
				(font
					(size 1.27 1.27)
					(thickness 0.15)
				)
				(justify left)
			)
		)
		(property "Value" "C_22u_0603"
			(at 58.42 121.92 0)
			(effects
				(font
					(size 1.27 1.27)
					(thickness 0.15)
				)
				(justify left bottom)
				(hide yes)
			)
		)
		(property "Footprint" "antmicro-footprints:C_0603_1608Metric"
			(at 60.96 121.92 0)
			(effects
				(font
					(size 1.27 1.27)
					(thickness 0.15)
				)
				(justify left bottom)
				(hide yes)
			)
		)
		(property "Datasheet" "https://www.murata.com/products/productdetail?partno=GRM188R60J226MEA0%23"
			(at 63.5 121.92 0)
			(effects
				(font
					(size 1.27 1.27)
					(thickness 0.15)
				)
				(justify left bottom)
				(hide yes)
			)
		)
		(property "Description" "SMD Multilayer Ceramic Capacitor, 22 µF, 6.3 V, 0603 [1608 Metric], ± 20%, X5R, GRM Series"
			(at 48.26 142.24 0)
			(effects
				(font
					(size 1.27 1.27)
				)
				(hide yes)
			)
		)
		(property "Manufacturer" "Murata"
			(at 68.58 121.92 0)
			(effects
				(font
					(size 1.27 1.27)
					(thickness 0.15)
				)
				(justify left bottom)
				(hide yes)
			)
		)
		(property "MPN" "GRM188R60J226MEA0D"
			(at 66.04 121.92 0)
			(effects
				(font
					(size 1.27 1.27)
					(thickness 0.15)
				)
				(justify left bottom)
				(hide yes)
			)
		)
		(property "Val" "22u"
			(at 47.625 141.605 90)
			(effects
				(font
					(size 1.27 1.27)
					(thickness 0.15)
				)
				(justify left)
			)
		)
		(property "License" "Apache-2.0"
			(at 71.12 121.92 0)
			(effects
				(font
					(size 1.27 1.27)
					(thickness 0.15)
				)
				(justify left bottom)
				(hide yes)
			)
		)
		(property "Author" "Antmicro"
			(at 73.66 121.92 0)
			(effects
				(font
					(size 1.27 1.27)
					(thickness 0.15)
				)
				(justify left bottom)
				(hide yes)
			)
		)
		(property "Voltage" ""
			(at 76.2 121.92 0)
			(effects
				(font
					(size 1.27 1.27)
				)
				(justify left bottom)
				(hide yes)
			)
		)
		(property "Dielectric" ""
			(at 78.74 121.92 0)
			(effects
				(font
					(size 1.27 1.27)
				)
				(justify left bottom)
				(hide yes)
			)
		)
		(pin "1"
		)
		(pin "2"
		)
		(instances
			(project "sdi-mipi-video-converter"
				(path ""
					(reference "C5")
					(unit 1)
				)
			)
		)
	)
	(symbol
		(lib_id "antmicroOperationalAmplifiers:LM339_TSSOP_CUSTOM_Split")
		(at 189.23 271.78 0)
		(unit 4)
		(exclude_from_sim no)
		(in_bom yes)
		(on_board yes)
		(dnp no)
		(fields_autoplaced yes)
		(property "Reference" "U3"
			(at 194.31 265.43 0)
			(effects
				(font
					(size 1.27 1.27)
					(thickness 0.15)
				)
			)
		)
		(property "Value" "LM339_TSSOP_Split"
			(at 194.31 265.43 0)
			(effects
				(font
					(size 1.27 1.27)
					(thickness 0.15)
				)
				(hide yes)
			)
		)
		(property "Footprint" "antmicro-footprints:TSSOP-14_4.4x5mm_P0.65mm"
			(at 214.63 281.94 0)
			(effects
				(font
					(size 1.27 1.27)
					(thickness 0.15)
				)
				(justify left bottom)
				(hide yes)
			)
		)
		(property "Datasheet" "https://www.ti.com/lit/ds/symlink/lm339b.pdf?ts=1679641364820&ref_url=https%253A%252F%252Fwww.google.com%252F"
			(at 214.63 284.48 0)
			(effects
				(font
					(size 1.27 1.27)
					(thickness 0.15)
				)
				(justify left bottom)
				(hide yes)
			)
		)
		(property "Description" "Analogue Comparator, Differential, 4 Comparators, 300 ns, 2V to 36V, TSSOP, 14 Pins"
			(at 214.63 297.18 0)
			(effects
				(font
					(size 1.27 1.27)
				)
				(justify left bottom)
				(hide yes)
			)
		)
		(property "MPN" "LM339PW"
			(at 194.31 267.97 0)
			(effects
				(font
					(size 1.27 1.27)
					(thickness 0.15)
				)
			)
		)
		(property "Manufacturer" "Texas Instruments"
			(at 214.63 289.56 0)
			(effects
				(font
					(size 1.27 1.27)
					(thickness 0.15)
				)
				(justify left bottom)
				(hide yes)
			)
		)
		(property "Author" "Antmicro"
			(at 214.63 292.1 0)
			(effects
				(font
					(size 1.27 1.27)
					(thickness 0.15)
				)
				(justify left bottom)
				(hide yes)
			)
		)
		(property "License" "Apache-2.0"
			(at 214.63 294.64 0)
			(effects
				(font
					(size 1.27 1.27)
					(thickness 0.15)
				)
				(justify left bottom)
				(hide yes)
			)
		)
		(pin "2"
		)
		(pin "4"
		)
		(pin "5"
		)
		(pin "1"
		)
		(pin "6"
		)
		(pin "7"
		)
		(pin "14"
		)
		(pin "8"
		)
		(pin "9"
		)
		(pin "10"
		)
		(pin "11"
		)
		(pin "13"
		)
		(pin "12"
		)
		(pin "3"
		)
		(instances
			(project "sdi-mipi-video-converter"
				(path ""
					(reference "U3")
					(unit 4)
				)
			)
		)
	)
	(symbol
		(lib_id "antmicroTransistorsFETsMOSFETsSingle:2N7002_SOT-23-3")
		(at 66.04 96.52 0)
		(unit 1)
		(exclude_from_sim no)
		(in_bom yes)
		(on_board yes)
		(dnp no)
		(fields_autoplaced yes)
		(property "Reference" "Q1"
			(at 77.47 92.7099 0)
			(effects
				(font
					(size 1.27 1.27)
					(thickness 0.15)
				)
				(justify left)
			)
		)
		(property "Value" "2N7002_SOT-23-3"
			(at 77.47 95.2499 0)
			(effects
				(font
					(size 1.27 1.27)
					(thickness 0.15)
				)
				(justify left)
			)
		)
		(property "Footprint" "antmicro-footprints:SOT-23-3"
			(at 88.9 106.68 0)
			(effects
				(font
					(size 1.27 1.27)
					(thickness 0.15)
				)
				(justify left bottom)
				(hide yes)
			)
		)
		(property "Datasheet" "https://www.onsemi.com/pub/Collateral/NDS7002A-D.PDF"
			(at 88.9 109.22 0)
			(effects
				(font
					(size 1.27 1.27)
					(thickness 0.15)
				)
				(justify left bottom)
				(hide yes)
			)
		)
		(property "Description" "Power MOSFET, N Channel, 60 V, 115 mA, 1.2 ohm, SOT-23, Surface Mount"
			(at 66.04 96.52 0)
			(effects
				(font
					(size 1.27 1.27)
				)
				(hide yes)
			)
		)
		(property "MPN" "2N7002"
			(at 88.9 111.76 0)
			(effects
				(font
					(size 1.27 1.27)
					(thickness 0.15)
				)
				(justify left bottom)
				(hide yes)
			)
		)
		(property "Manufacturer" "ON Semiconductor"
			(at 88.9 114.3 0)
			(effects
				(font
					(size 1.27 1.27)
					(thickness 0.15)
				)
				(justify left bottom)
				(hide yes)
			)
		)
		(property "Author" "Antmicro"
			(at 88.9 116.84 0)
			(effects
				(font
					(size 1.27 1.27)
					(thickness 0.15)
				)
				(justify left bottom)
				(hide yes)
			)
		)
		(property "License" "Apache-2.0"
			(at 88.9 119.38 0)
			(effects
				(font
					(size 1.27 1.27)
					(thickness 0.15)
				)
				(justify left bottom)
				(hide yes)
			)
		)
		(pin "1"
		)
		(pin "2"
		)
		(pin "3"
		)
		(instances
			(project "sdi-mipi-video-converter"
				(path ""
					(reference "Q1")
					(unit 1)
				)
			)
		)
	)
	(symbol
		(lib_id "antmicropower:GND")
		(at 113.03 88.9 0)
		(unit 1)
		(exclude_from_sim no)
		(in_bom yes)
		(on_board yes)
		(dnp no)
		(fields_autoplaced yes)
		(property "Reference" "#PWR0218"
			(at 121.92 91.44 0)
			(effects
				(font
					(size 1.27 1.27)
					(thickness 0.15)
				)
				(justify left bottom)
				(hide yes)
			)
		)
		(property "Value" "GND"
			(at 113.03 93.98 0)
			(effects
				(font
					(size 1.27 1.27)
					(thickness 0.15)
				)
			)
		)
		(property "Footprint" ""
			(at 121.92 96.52 0)
			(effects
				(font
					(size 1.27 1.27)
					(thickness 0.15)
				)
				(justify left bottom)
				(hide yes)
			)
		)
		(property "Datasheet" ""
			(at 121.92 101.6 0)
			(effects
				(font
					(size 1.27 1.27)
					(thickness 0.15)
				)
				(justify left bottom)
				(hide yes)
			)
		)
		(property "Description" ""
			(at 113.03 88.9 0)
			(effects
				(font
					(size 1.27 1.27)
				)
				(hide yes)
			)
		)
		(property "Author" "Antmicro"
			(at 121.92 96.52 0)
			(effects
				(font
					(size 1.27 1.27)
					(thickness 0.15)
				)
				(justify left bottom)
				(hide yes)
			)
		)
		(property "License" "Apache-2.0"
			(at 121.92 99.06 0)
			(effects
				(font
					(size 1.27 1.27)
					(thickness 0.15)
				)
				(justify left bottom)
				(hide yes)
			)
		)
		(pin "1"
		)
		(instances
			(project "sdi-mipi-video-converter"
				(path ""
					(reference "#PWR0218")
					(unit 1)
				)
			)
		)
	)
	(symbol
		(lib_id "antmicroCapacitors0402:C_100n_0402")
		(at 86.36 153.67 270)
		(mirror x)
		(unit 1)
		(exclude_from_sim no)
		(in_bom yes)
		(on_board yes)
		(dnp no)
		(fields_autoplaced yes)
		(property "Reference" "C6"
			(at 88.9 149.8535 90)
			(effects
				(font
					(size 1.27 1.27)
					(thickness 0.15)
				)
				(justify left)
			)
		)
		(property "Value" "C_100n_0402"
			(at 76.2 133.35 0)
			(effects
				(font
					(size 1.27 1.27)
					(thickness 0.15)
				)
				(justify left bottom)
				(hide yes)
			)
		)
		(property "Footprint" "antmicro-footprints:C_0402_1005Metric"
			(at 73.66 133.35 0)
			(effects
				(font
					(size 1.27 1.27)
					(thickness 0.15)
				)
				(justify left bottom)
				(hide yes)
			)
		)
		(property "Datasheet" "https://www.murata.com/products/productdetail?partno=GRM155R61H104KE14%23"
			(at 71.12 133.35 0)
			(effects
				(font
					(size 1.27 1.27)
					(thickness 0.15)
				)
				(justify left bottom)
				(hide yes)
			)
		)
		(property "Description" "SMD Multilayer Ceramic Capacitor, 0.1 µF, 50 V, 0402 [1005 Metric], ± 10%, X5R, GRM Series"
			(at 86.36 153.67 0)
			(effects
				(font
					(size 1.27 1.27)
				)
				(hide yes)
			)
		)
		(property "Manufacturer" "Murata"
			(at 66.04 133.35 0)
			(effects
				(font
					(size 1.27 1.27)
					(thickness 0.15)
				)
				(justify left bottom)
				(hide yes)
			)
		)
		(property "MPN" "GRM155R61H104KE14D"
			(at 68.58 133.35 0)
			(effects
				(font
					(size 1.27 1.27)
					(thickness 0.15)
				)
				(justify left bottom)
				(hide yes)
			)
		)
		(property "Val" "100n"
			(at 88.9 152.3935 90)
			(effects
				(font
					(size 1.27 1.27)
					(thickness 0.15)
				)
				(justify left)
			)
		)
		(property "License" "Apache-2.0"
			(at 63.5 133.35 0)
			(effects
				(font
					(size 1.27 1.27)
					(thickness 0.15)
				)
				(justify left bottom)
				(hide yes)
			)
		)
		(property "Author" "Antmicro"
			(at 60.96 133.35 0)
			(effects
				(font
					(size 1.27 1.27)
					(thickness 0.15)
				)
				(justify left bottom)
				(hide yes)
			)
		)
		(property "Voltage" "50V"
			(at 58.42 133.35 0)
			(effects
				(font
					(size 1.27 1.27)
				)
				(justify left bottom)
				(hide yes)
			)
		)
		(property "Dielectric" "X5R"
			(at 55.88 133.35 0)
			(effects
				(font
					(size 1.27 1.27)
				)
				(justify left bottom)
				(hide yes)
			)
		)
		(pin "1"
		)
		(pin "2"
		)
		(instances
			(project "sdi-mipi-video-converter"
				(path ""
					(reference "C6")
					(unit 1)
				)
			)
		)
	)
	(symbol
		(lib_id "antmicropower:GND")
		(at 106.68 88.9 0)
		(unit 1)
		(exclude_from_sim no)
		(in_bom yes)
		(on_board yes)
		(dnp no)
		(fields_autoplaced yes)
		(property "Reference" "#PWR0246"
			(at 115.57 91.44 0)
			(effects
				(font
					(size 1.27 1.27)
					(thickness 0.15)
				)
				(justify left bottom)
				(hide yes)
			)
		)
		(property "Value" "GND"
			(at 106.68 93.98 0)
			(effects
				(font
					(size 1.27 1.27)
					(thickness 0.15)
				)
			)
		)
		(property "Footprint" ""
			(at 115.57 96.52 0)
			(effects
				(font
					(size 1.27 1.27)
					(thickness 0.15)
				)
				(justify left bottom)
				(hide yes)
			)
		)
		(property "Datasheet" ""
			(at 115.57 101.6 0)
			(effects
				(font
					(size 1.27 1.27)
					(thickness 0.15)
				)
				(justify left bottom)
				(hide yes)
			)
		)
		(property "Description" ""
			(at 106.68 88.9 0)
			(effects
				(font
					(size 1.27 1.27)
				)
				(hide yes)
			)
		)
		(property "Author" "Antmicro"
			(at 115.57 96.52 0)
			(effects
				(font
					(size 1.27 1.27)
					(thickness 0.15)
				)
				(justify left bottom)
				(hide yes)
			)
		)
		(property "License" "Apache-2.0"
			(at 115.57 99.06 0)
			(effects
				(font
					(size 1.27 1.27)
					(thickness 0.15)
				)
				(justify left bottom)
				(hide yes)
			)
		)
		(pin "1"
		)
		(instances
			(project "sdi-mipi-video-converter"
				(path ""
					(reference "#PWR0246")
					(unit 1)
				)
			)
		)
	)
	(symbol
		(lib_id "antmicropower:+3.3V")
		(at 77.47 228.6 0)
		(unit 1)
		(exclude_from_sim no)
		(in_bom yes)
		(on_board yes)
		(dnp no)
		(fields_autoplaced yes)
		(property "Reference" "#PWR016"
			(at 77.47 232.41 0)
			(effects
				(font
					(size 1.27 1.27)
				)
				(hide yes)
			)
		)
		(property "Value" "+3V3"
			(at 77.47 223.52 0)
			(effects
				(font
					(size 1.27 1.27)
				)
			)
		)
		(property "Footprint" ""
			(at 77.47 228.6 0)
			(effects
				(font
					(size 1.27 1.27)
				)
				(hide yes)
			)
		)
		(property "Datasheet" ""
			(at 77.47 228.6 0)
			(effects
				(font
					(size 1.27 1.27)
				)
				(hide yes)
			)
		)
		(property "Description" ""
			(at 77.47 228.6 0)
			(effects
				(font
					(size 1.27 1.27)
				)
				(hide yes)
			)
		)
		(pin "1"
		)
		(instances
			(project "sdi-mipi-video-converter"
				(path ""
					(reference "#PWR016")
					(unit 1)
				)
			)
		)
	)
	(symbol
		(lib_id "antmicropower:GND")
		(at 297.18 170.18 0)
		(unit 1)
		(exclude_from_sim no)
		(in_bom yes)
		(on_board yes)
		(dnp no)
		(fields_autoplaced yes)
		(property "Reference" "#PWR048"
			(at 306.07 172.72 0)
			(effects
				(font
					(size 1.27 1.27)
					(thickness 0.15)
				)
				(justify left bottom)
				(hide yes)
			)
		)
		(property "Value" "GND"
			(at 297.18 175.26 0)
			(effects
				(font
					(size 1.27 1.27)
					(thickness 0.15)
				)
			)
		)
		(property "Footprint" ""
			(at 306.07 177.8 0)
			(effects
				(font
					(size 1.27 1.27)
					(thickness 0.15)
				)
				(justify left bottom)
				(hide yes)
			)
		)
		(property "Datasheet" ""
			(at 306.07 182.88 0)
			(effects
				(font
					(size 1.27 1.27)
					(thickness 0.15)
				)
				(justify left bottom)
				(hide yes)
			)
		)
		(property "Description" ""
			(at 297.18 170.18 0)
			(effects
				(font
					(size 1.27 1.27)
				)
				(hide yes)
			)
		)
		(property "Author" "Antmicro"
			(at 306.07 177.8 0)
			(effects
				(font
					(size 1.27 1.27)
					(thickness 0.15)
				)
				(justify left bottom)
				(hide yes)
			)
		)
		(property "License" "Apache-2.0"
			(at 306.07 180.34 0)
			(effects
				(font
					(size 1.27 1.27)
					(thickness 0.15)
				)
				(justify left bottom)
				(hide yes)
			)
		)
		(pin "1"
		)
		(instances
			(project "sdi-mipi-video-converter"
				(path ""
					(reference "#PWR048")
					(unit 1)
				)
			)
		)
	)
	(symbol
		(lib_id "antmicropower:+1V2")
		(at 119.38 267.97 0)
		(unit 1)
		(exclude_from_sim no)
		(in_bom yes)
		(on_board yes)
		(dnp no)
		(fields_autoplaced yes)
		(property "Reference" "#PWR020"
			(at 119.38 271.78 0)
			(effects
				(font
					(size 1.27 1.27)
				)
				(hide yes)
			)
		)
		(property "Value" "+1V2"
			(at 119.38 262.89 0)
			(effects
				(font
					(size 1.27 1.27)
				)
			)
		)
		(property "Footprint" ""
			(at 119.38 267.97 0)
			(effects
				(font
					(size 1.27 1.27)
				)
				(hide yes)
			)
		)
		(property "Datasheet" ""
			(at 119.38 267.97 0)
			(effects
				(font
					(size 1.27 1.27)
				)
				(hide yes)
			)
		)
		(property "Description" ""
			(at 119.38 267.97 0)
			(effects
				(font
					(size 1.27 1.27)
				)
				(hide yes)
			)
		)
		(pin "1"
		)
		(instances
			(project "sdi-mipi-video-converter"
				(path ""
					(reference "#PWR020")
					(unit 1)
				)
			)
		)
	)
	(symbol
		(lib_id "antmicropower:+5V")
		(at 229.87 228.6 0)
		(unit 1)
		(exclude_from_sim no)
		(in_bom yes)
		(on_board yes)
		(dnp no)
		(fields_autoplaced yes)
		(property "Reference" "#PWR040"
			(at 245.11 231.14 0)
			(effects
				(font
					(size 1.27 1.27)
					(thickness 0.15)
				)
				(justify left bottom)
				(hide yes)
			)
		)
		(property "Value" "+5V"
			(at 229.87 223.52 0)
			(effects
				(font
					(size 1.27 1.27)
					(thickness 0.15)
				)
			)
		)
		(property "Footprint" ""
			(at 245.11 236.22 0)
			(effects
				(font
					(size 1.27 1.27)
					(thickness 0.15)
				)
				(justify left bottom)
				(hide yes)
			)
		)
		(property "Datasheet" ""
			(at 245.11 238.76 0)
			(effects
				(font
					(size 1.27 1.27)
					(thickness 0.15)
				)
				(justify left bottom)
				(hide yes)
			)
		)
		(property "Description" ""
			(at 229.87 228.6 0)
			(effects
				(font
					(size 1.27 1.27)
				)
				(hide yes)
			)
		)
		(property "Author" "Antmicro"
			(at 245.11 236.22 0)
			(effects
				(font
					(size 1.27 1.27)
					(thickness 0.15)
				)
				(justify left bottom)
				(hide yes)
			)
		)
		(property "License" "Apache-2.0"
			(at 245.11 238.76 0)
			(effects
				(font
					(size 1.27 1.27)
					(thickness 0.15)
				)
				(justify left bottom)
				(hide yes)
			)
		)
		(pin "1"
		)
		(instances
			(project "sdi-mipi-video-converter"
				(path ""
					(reference "#PWR040")
					(unit 1)
				)
			)
		)
	)
	(symbol
		(lib_id "antmicroOperationalAmplifiers:LM339_TSSOP_CUSTOM_Split")
		(at 189.23 231.14 0)
		(unit 4)
		(exclude_from_sim no)
		(in_bom yes)
		(on_board yes)
		(dnp no)
		(fields_autoplaced yes)
		(property "Reference" "U2"
			(at 194.31 224.79 0)
			(effects
				(font
					(size 1.27 1.27)
					(thickness 0.15)
				)
			)
		)
		(property "Value" "LM339_TSSOP_Split"
			(at 194.31 224.79 0)
			(effects
				(font
					(size 1.27 1.27)
					(thickness 0.15)
				)
				(hide yes)
			)
		)
		(property "Footprint" "antmicro-footprints:TSSOP-14_4.4x5mm_P0.65mm"
			(at 214.63 241.3 0)
			(effects
				(font
					(size 1.27 1.27)
					(thickness 0.15)
				)
				(justify left bottom)
				(hide yes)
			)
		)
		(property "Datasheet" "https://www.ti.com/lit/ds/symlink/lm339b.pdf?ts=1679641364820&ref_url=https%253A%252F%252Fwww.google.com%252F"
			(at 214.63 243.84 0)
			(effects
				(font
					(size 1.27 1.27)
					(thickness 0.15)
				)
				(justify left bottom)
				(hide yes)
			)
		)
		(property "Description" "Analogue Comparator, Differential, 4 Comparators, 300 ns, 2V to 36V, TSSOP, 14 Pins"
			(at 214.63 256.54 0)
			(effects
				(font
					(size 1.27 1.27)
				)
				(justify left bottom)
				(hide yes)
			)
		)
		(property "MPN" "LM339PW"
			(at 194.31 227.33 0)
			(effects
				(font
					(size 1.27 1.27)
					(thickness 0.15)
				)
			)
		)
		(property "Manufacturer" "Texas Instruments"
			(at 214.63 248.92 0)
			(effects
				(font
					(size 1.27 1.27)
					(thickness 0.15)
				)
				(justify left bottom)
				(hide yes)
			)
		)
		(property "Author" "Antmicro"
			(at 214.63 251.46 0)
			(effects
				(font
					(size 1.27 1.27)
					(thickness 0.15)
				)
				(justify left bottom)
				(hide yes)
			)
		)
		(property "License" "Apache-2.0"
			(at 214.63 254 0)
			(effects
				(font
					(size 1.27 1.27)
					(thickness 0.15)
				)
				(justify left bottom)
				(hide yes)
			)
		)
		(pin "2"
		)
		(pin "4"
		)
		(pin "5"
		)
		(pin "1"
		)
		(pin "6"
		)
		(pin "7"
		)
		(pin "14"
		)
		(pin "8"
		)
		(pin "9"
		)
		(pin "10"
		)
		(pin "11"
		)
		(pin "13"
		)
		(pin "12"
		)
		(pin "3"
		)
		(instances
			(project "sdi-mipi-video-converter"
				(path ""
					(reference "U2")
					(unit 4)
				)
			)
		)
	)
	(symbol
		(lib_id "antmicroResistors0402:R_18k7_0402")
		(at 345.44 233.68 90)
		(unit 1)
		(exclude_from_sim no)
		(in_bom yes)
		(on_board yes)
		(dnp no)
		(fields_autoplaced yes)
		(property "Reference" "R35"
			(at 342.9 229.8699 90)
			(effects
				(font
					(size 1.27 1.27)
					(thickness 0.15)
				)
				(justify left)
			)
		)
		(property "Value" "R_18k7_0402"
			(at 358.14 213.36 0)
			(effects
				(font
					(size 1.27 1.27)
					(thickness 0.15)
				)
				(justify left bottom)
				(hide yes)
			)
		)
		(property "Footprint" "antmicro-footprints:R_0402_1005Metric"
			(at 360.68 213.36 0)
			(effects
				(font
					(size 1.27 1.27)
					(thickness 0.15)
				)
				(justify left bottom)
				(hide yes)
			)
		)
		(property "Datasheet" "https://www.bourns.com/docs/product-datasheets/cr.pdf"
			(at 363.22 213.36 0)
			(effects
				(font
					(size 1.27 1.27)
					(thickness 0.15)
				)
				(justify left bottom)
				(hide yes)
			)
		)
		(property "Description" "SMD Chip Resistor"
			(at 345.44 233.68 0)
			(effects
				(font
					(size 1.27 1.27)
				)
				(hide yes)
			)
		)
		(property "Manufacturer" "Bourns"
			(at 368.3 213.36 0)
			(effects
				(font
					(size 1.27 1.27)
					(thickness 0.15)
				)
				(justify left bottom)
				(hide yes)
			)
		)
		(property "MPN" "CR0402-FX-1872GLF"
			(at 365.76 213.36 0)
			(effects
				(font
					(size 1.27 1.27)
					(thickness 0.15)
				)
				(justify left bottom)
				(hide yes)
			)
		)
		(property "Val" "18k7"
			(at 342.9 232.4099 90)
			(effects
				(font
					(size 1.27 1.27)
					(thickness 0.15)
				)
				(justify left)
			)
		)
		(property "License" "Apache-2.0"
			(at 370.84 213.36 0)
			(effects
				(font
					(size 1.27 1.27)
					(thickness 0.15)
				)
				(justify left bottom)
				(hide yes)
			)
		)
		(property "Author" "Antmicro"
			(at 373.38 213.36 0)
			(effects
				(font
					(size 1.27 1.27)
					(thickness 0.15)
				)
				(justify left bottom)
				(hide yes)
			)
		)
		(property "Tolerance" "1%"
			(at 355.6 213.36 0)
			(effects
				(font
					(size 1.27 1.27)
				)
				(justify left bottom)
				(hide yes)
			)
		)
		(pin "1"
		)
		(pin "2"
		)
		(instances
			(project "sdi-mipi-video-converter"
				(path ""
					(reference "R35")
					(unit 1)
				)
			)
		)
	)
	(symbol
		(lib_id "antmicroResistors0402:R_10k_0402")
		(at 337.82 57.15 90)
		(unit 1)
		(exclude_from_sim no)
		(in_bom yes)
		(on_board yes)
		(dnp no)
		(fields_autoplaced yes)
		(property "Reference" "R27"
			(at 335.28 53.3399 90)
			(effects
				(font
					(size 1.27 1.27)
					(thickness 0.15)
				)
				(justify left)
			)
		)
		(property "Value" "R_10k_0402"
			(at 350.52 36.83 0)
			(effects
				(font
					(size 1.27 1.27)
					(thickness 0.15)
				)
				(justify left bottom)
				(hide yes)
			)
		)
		(property "Footprint" "antmicro-footprints:R_0402_1005Metric"
			(at 353.06 36.83 0)
			(effects
				(font
					(size 1.27 1.27)
					(thickness 0.15)
				)
				(justify left bottom)
				(hide yes)
			)
		)
		(property "Datasheet" "https://www.bourns.com/docs/product-datasheets/cr.pdf"
			(at 355.6 36.83 0)
			(effects
				(font
					(size 1.27 1.27)
					(thickness 0.15)
				)
				(justify left bottom)
				(hide yes)
			)
		)
		(property "Description" "SMD Chip Resistor, 10 kohm, ± 1%, 62.5 mW, 0402 [1005 Metric], Thick Film, General Purpose"
			(at 337.82 57.15 0)
			(effects
				(font
					(size 1.27 1.27)
				)
				(hide yes)
			)
		)
		(property "Manufacturer" "Bourns"
			(at 360.68 36.83 0)
			(effects
				(font
					(size 1.27 1.27)
					(thickness 0.15)
				)
				(justify left bottom)
				(hide yes)
			)
		)
		(property "MPN" "CR0402-FX-1002GLF"
			(at 358.14 36.83 0)
			(effects
				(font
					(size 1.27 1.27)
					(thickness 0.15)
				)
				(justify left bottom)
				(hide yes)
			)
		)
		(property "Val" "10k"
			(at 335.28 55.8799 90)
			(effects
				(font
					(size 1.27 1.27)
					(thickness 0.15)
				)
				(justify left)
			)
		)
		(property "License" "Apache-2.0"
			(at 363.22 36.83 0)
			(effects
				(font
					(size 1.27 1.27)
					(thickness 0.15)
				)
				(justify left bottom)
				(hide yes)
			)
		)
		(property "Author" "Antmicro"
			(at 365.76 36.83 0)
			(effects
				(font
					(size 1.27 1.27)
					(thickness 0.15)
				)
				(justify left bottom)
				(hide yes)
			)
		)
		(property "Tolerance" "1%"
			(at 347.98 36.83 0)
			(effects
				(font
					(size 1.27 1.27)
				)
				(justify left bottom)
				(hide yes)
			)
		)
		(pin "1"
		)
		(pin "2"
		)
		(instances
			(project "sdi-mipi-video-converter"
				(path ""
					(reference "R27")
					(unit 1)
				)
			)
		)
	)
	(symbol
		(lib_id "antmicroResistors0402:R_1k3_0402")
		(at 336.55 113.03 90)
		(unit 1)
		(exclude_from_sim no)
		(in_bom yes)
		(on_board yes)
		(dnp no)
		(fields_autoplaced yes)
		(property "Reference" "R10"
			(at 339.09 109.2199 90)
			(effects
				(font
					(size 1.27 1.27)
					(thickness 0.15)
				)
				(justify right)
			)
		)
		(property "Value" "R_1k3_0402"
			(at 349.25 92.71 0)
			(effects
				(font
					(size 1.27 1.27)
					(thickness 0.15)
				)
				(justify left bottom)
				(hide yes)
			)
		)
		(property "Footprint" "antmicro-footprints:R_0402_1005Metric"
			(at 351.79 92.71 0)
			(effects
				(font
					(size 1.27 1.27)
					(thickness 0.15)
				)
				(justify left bottom)
				(hide yes)
			)
		)
		(property "Datasheet" "https://www.bourns.com/docs/product-datasheets/cr.pdf"
			(at 354.33 92.71 0)
			(effects
				(font
					(size 1.27 1.27)
					(thickness 0.15)
				)
				(justify left bottom)
				(hide yes)
			)
		)
		(property "Description" "SMD Chip Resistor, 1.3 kohm, ± 1%, 62.5 mW, 0402 [1005 Metric], Thick Film, General Purpose"
			(at 336.55 113.03 0)
			(effects
				(font
					(size 1.27 1.27)
				)
				(hide yes)
			)
		)
		(property "Manufacturer" "Bourns"
			(at 359.41 92.71 0)
			(effects
				(font
					(size 1.27 1.27)
					(thickness 0.15)
				)
				(justify left bottom)
				(hide yes)
			)
		)
		(property "MPN" "CR0402-FX-1301GLF"
			(at 356.87 92.71 0)
			(effects
				(font
					(size 1.27 1.27)
					(thickness 0.15)
				)
				(justify left bottom)
				(hide yes)
			)
		)
		(property "Val" "1k3"
			(at 339.09 111.7599 90)
			(effects
				(font
					(size 1.27 1.27)
					(thickness 0.15)
				)
				(justify right)
			)
		)
		(property "License" "Apache-2.0"
			(at 361.95 92.71 0)
			(effects
				(font
					(size 1.27 1.27)
					(thickness 0.15)
				)
				(justify left bottom)
				(hide yes)
			)
		)
		(property "Author" "Antmicro"
			(at 364.49 92.71 0)
			(effects
				(font
					(size 1.27 1.27)
					(thickness 0.15)
				)
				(justify left bottom)
				(hide yes)
			)
		)
		(property "Tolerance" "1%"
			(at 346.71 92.71 0)
			(effects
				(font
					(size 1.27 1.27)
				)
				(justify left bottom)
				(hide yes)
			)
		)
		(pin "1"
		)
		(pin "2"
		)
		(instances
			(project "sdi-mipi-video-converter"
				(path ""
					(reference "R10")
					(unit 1)
				)
			)
		)
	)
	(symbol
		(lib_id "antmicropower:GND")
		(at 388.62 91.44 0)
		(unit 1)
		(exclude_from_sim no)
		(in_bom yes)
		(on_board yes)
		(dnp no)
		(fields_autoplaced yes)
		(property "Reference" "#PWR076"
			(at 397.51 93.98 0)
			(effects
				(font
					(size 1.27 1.27)
					(thickness 0.15)
				)
				(justify left bottom)
				(hide yes)
			)
		)
		(property "Value" "GND"
			(at 386.08 92.7099 0)
			(effects
				(font
					(size 1.27 1.27)
					(thickness 0.15)
				)
				(justify right)
			)
		)
		(property "Footprint" ""
			(at 397.51 99.06 0)
			(effects
				(font
					(size 1.27 1.27)
					(thickness 0.15)
				)
				(justify left bottom)
				(hide yes)
			)
		)
		(property "Datasheet" ""
			(at 397.51 104.14 0)
			(effects
				(font
					(size 1.27 1.27)
					(thickness 0.15)
				)
				(justify left bottom)
				(hide yes)
			)
		)
		(property "Description" ""
			(at 388.62 91.44 0)
			(effects
				(font
					(size 1.27 1.27)
				)
				(hide yes)
			)
		)
		(property "Author" "Antmicro"
			(at 397.51 99.06 0)
			(effects
				(font
					(size 1.27 1.27)
					(thickness 0.15)
				)
				(justify left bottom)
				(hide yes)
			)
		)
		(property "License" "Apache-2.0"
			(at 397.51 101.6 0)
			(effects
				(font
					(size 1.27 1.27)
					(thickness 0.15)
				)
				(justify left bottom)
				(hide yes)
			)
		)
		(pin "1"
		)
		(instances
			(project "sdi-mipi-video-converter"
				(path ""
					(reference "#PWR076")
					(unit 1)
				)
			)
		)
	)
	(symbol
		(lib_id "antmicropower:GND")
		(at 367.03 58.42 0)
		(unit 1)
		(exclude_from_sim no)
		(in_bom yes)
		(on_board yes)
		(dnp no)
		(fields_autoplaced yes)
		(property "Reference" "#PWR064"
			(at 375.92 60.96 0)
			(effects
				(font
					(size 1.27 1.27)
					(thickness 0.15)
				)
				(justify left bottom)
				(hide yes)
			)
		)
		(property "Value" "GND"
			(at 364.49 59.6899 0)
			(effects
				(font
					(size 1.27 1.27)
					(thickness 0.15)
				)
				(justify right)
			)
		)
		(property "Footprint" ""
			(at 375.92 66.04 0)
			(effects
				(font
					(size 1.27 1.27)
					(thickness 0.15)
				)
				(justify left bottom)
				(hide yes)
			)
		)
		(property "Datasheet" ""
			(at 375.92 71.12 0)
			(effects
				(font
					(size 1.27 1.27)
					(thickness 0.15)
				)
				(justify left bottom)
				(hide yes)
			)
		)
		(property "Description" ""
			(at 367.03 58.42 0)
			(effects
				(font
					(size 1.27 1.27)
				)
				(hide yes)
			)
		)
		(property "Author" "Antmicro"
			(at 375.92 66.04 0)
			(effects
				(font
					(size 1.27 1.27)
					(thickness 0.15)
				)
				(justify left bottom)
				(hide yes)
			)
		)
		(property "License" "Apache-2.0"
			(at 375.92 68.58 0)
			(effects
				(font
					(size 1.27 1.27)
					(thickness 0.15)
				)
				(justify left bottom)
				(hide yes)
			)
		)
		(pin "1"
		)
		(instances
			(project "sdi-mipi-video-converter"
				(path ""
					(reference "#PWR064")
					(unit 1)
				)
			)
		)
	)
	(symbol
		(lib_id "antmicroOperationalAmplifiers:LM339_TSSOP_CUSTOM_Split")
		(at 71.12 195.58 0)
		(unit 5)
		(exclude_from_sim no)
		(in_bom yes)
		(on_board yes)
		(dnp no)
		(fields_autoplaced yes)
		(property "Reference" "U3"
			(at 80.01 194.31 0)
			(effects
				(font
					(size 1.27 1.27)
					(thickness 0.15)
				)
				(justify left)
			)
		)
		(property "Value" "LM339_TSSOP_Split"
			(at 80.01 196.85 0)
			(effects
				(font
					(size 1.27 1.27)
					(thickness 0.15)
				)
				(justify left)
			)
		)
		(property "Footprint" "antmicro-footprints:TSSOP-14_4.4x5mm_P0.65mm"
			(at 96.52 205.74 0)
			(effects
				(font
					(size 1.27 1.27)
					(thickness 0.15)
				)
				(justify left bottom)
				(hide yes)
			)
		)
		(property "Datasheet" "https://www.ti.com/lit/ds/symlink/lm339b.pdf?ts=1679641364820&ref_url=https%253A%252F%252Fwww.google.com%252F"
			(at 96.52 208.28 0)
			(effects
				(font
					(size 1.27 1.27)
					(thickness 0.15)
				)
				(justify left bottom)
				(hide yes)
			)
		)
		(property "Description" "Analogue Comparator, Differential, 4 Comparators, 300 ns, 2V to 36V, TSSOP, 14 Pins"
			(at 96.52 220.98 0)
			(effects
				(font
					(size 1.27 1.27)
				)
				(justify left bottom)
				(hide yes)
			)
		)
		(property "MPN" "LM339PW"
			(at 80.01 199.39 0)
			(effects
				(font
					(size 1.27 1.27)
					(thickness 0.15)
				)
				(justify left)
			)
		)
		(property "Manufacturer" "Texas Instruments"
			(at 96.52 213.36 0)
			(effects
				(font
					(size 1.27 1.27)
					(thickness 0.15)
				)
				(justify left bottom)
				(hide yes)
			)
		)
		(property "Author" "Antmicro"
			(at 96.52 215.9 0)
			(effects
				(font
					(size 1.27 1.27)
					(thickness 0.15)
				)
				(justify left bottom)
				(hide yes)
			)
		)
		(property "License" "Apache-2.0"
			(at 96.52 218.44 0)
			(effects
				(font
					(size 1.27 1.27)
					(thickness 0.15)
				)
				(justify left bottom)
				(hide yes)
			)
		)
		(pin "2"
		)
		(pin "4"
		)
		(pin "5"
		)
		(pin "1"
		)
		(pin "6"
		)
		(pin "7"
		)
		(pin "14"
		)
		(pin "8"
		)
		(pin "9"
		)
		(pin "10"
		)
		(pin "11"
		)
		(pin "13"
		)
		(pin "12"
		)
		(pin "3"
		)
		(instances
			(project "sdi-mipi-video-converter"
				(path ""
					(reference "U3")
					(unit 5)
				)
			)
		)
	)
	(symbol
		(lib_id "antmicropower:GND")
		(at 270.51 50.8 0)
		(unit 1)
		(exclude_from_sim no)
		(in_bom yes)
		(on_board yes)
		(dnp no)
		(fields_autoplaced yes)
		(property "Reference" "#PWR038"
			(at 279.4 53.34 0)
			(effects
				(font
					(size 1.27 1.27)
					(thickness 0.15)
				)
				(justify left bottom)
				(hide yes)
			)
		)
		(property "Value" "GND"
			(at 270.51 55.88 0)
			(effects
				(font
					(size 1.27 1.27)
					(thickness 0.15)
				)
			)
		)
		(property "Footprint" ""
			(at 279.4 58.42 0)
			(effects
				(font
					(size 1.27 1.27)
					(thickness 0.15)
				)
				(justify left bottom)
				(hide yes)
			)
		)
		(property "Datasheet" ""
			(at 279.4 63.5 0)
			(effects
				(font
					(size 1.27 1.27)
					(thickness 0.15)
				)
				(justify left bottom)
				(hide yes)
			)
		)
		(property "Description" ""
			(at 270.51 50.8 0)
			(effects
				(font
					(size 1.27 1.27)
				)
				(hide yes)
			)
		)
		(property "Author" "Antmicro"
			(at 279.4 58.42 0)
			(effects
				(font
					(size 1.27 1.27)
					(thickness 0.15)
				)
				(justify left bottom)
				(hide yes)
			)
		)
		(property "License" "Apache-2.0"
			(at 279.4 60.96 0)
			(effects
				(font
					(size 1.27 1.27)
					(thickness 0.15)
				)
				(justify left bottom)
				(hide yes)
			)
		)
		(pin "1"
		)
		(instances
			(project "sdi-mipi-video-converter"
				(path ""
					(reference "#PWR038")
					(unit 1)
				)
			)
		)
	)
	(symbol
		(lib_id "antmicropower:GND")
		(at 59.69 104.14 0)
		(unit 1)
		(exclude_from_sim no)
		(in_bom yes)
		(on_board yes)
		(dnp no)
		(fields_autoplaced yes)
		(property "Reference" "#PWR0244"
			(at 68.58 106.68 0)
			(effects
				(font
					(size 1.27 1.27)
					(thickness 0.15)
				)
				(justify left bottom)
				(hide yes)
			)
		)
		(property "Value" "GND"
			(at 59.69 109.22 0)
			(effects
				(font
					(size 1.27 1.27)
					(thickness 0.15)
				)
			)
		)
		(property "Footprint" ""
			(at 68.58 111.76 0)
			(effects
				(font
					(size 1.27 1.27)
					(thickness 0.15)
				)
				(justify left bottom)
				(hide yes)
			)
		)
		(property "Datasheet" ""
			(at 68.58 116.84 0)
			(effects
				(font
					(size 1.27 1.27)
					(thickness 0.15)
				)
				(justify left bottom)
				(hide yes)
			)
		)
		(property "Description" ""
			(at 59.69 104.14 0)
			(effects
				(font
					(size 1.27 1.27)
				)
				(hide yes)
			)
		)
		(property "Author" "Antmicro"
			(at 68.58 111.76 0)
			(effects
				(font
					(size 1.27 1.27)
					(thickness 0.15)
				)
				(justify left bottom)
				(hide yes)
			)
		)
		(property "License" "Apache-2.0"
			(at 68.58 114.3 0)
			(effects
				(font
					(size 1.27 1.27)
					(thickness 0.15)
				)
				(justify left bottom)
				(hide yes)
			)
		)
		(pin "1"
		)
		(instances
			(project "sdi-mipi-video-converter"
				(path ""
					(reference "#PWR0244")
					(unit 1)
				)
			)
		)
	)
	(symbol
		(lib_id "antmicroCapacitors0402:C_100n_0402")
		(at 19.05 198.12 90)
		(unit 1)
		(exclude_from_sim no)
		(in_bom yes)
		(on_board yes)
		(dnp no)
		(property "Reference" "C1"
			(at 20.955 194.31 90)
			(effects
				(font
					(size 1.27 1.27)
					(thickness 0.15)
				)
				(justify right)
			)
		)
		(property "Value" "C_100n_0402"
			(at 29.21 177.8 0)
			(effects
				(font
					(size 1.27 1.27)
					(thickness 0.15)
				)
				(justify left bottom)
				(hide yes)
			)
		)
		(property "Footprint" "antmicro-footprints:C_0402_1005Metric"
			(at 31.75 177.8 0)
			(effects
				(font
					(size 1.27 1.27)
					(thickness 0.15)
				)
				(justify left bottom)
				(hide yes)
			)
		)
		(property "Datasheet" "https://www.murata.com/products/productdetail?partno=GRM155R61H104KE14%23"
			(at 34.29 177.8 0)
			(effects
				(font
					(size 1.27 1.27)
					(thickness 0.15)
				)
				(justify left bottom)
				(hide yes)
			)
		)
		(property "Description" "SMD Multilayer Ceramic Capacitor, 0.1 µF, 50 V, 0402 [1005 Metric], ± 10%, X5R, GRM Series"
			(at 19.05 198.12 0)
			(effects
				(font
					(size 1.27 1.27)
				)
				(hide yes)
			)
		)
		(property "Manufacturer" "Murata"
			(at 39.37 177.8 0)
			(effects
				(font
					(size 1.27 1.27)
					(thickness 0.15)
				)
				(justify left bottom)
				(hide yes)
			)
		)
		(property "MPN" "GRM155R61H104KE14D"
			(at 36.83 177.8 0)
			(effects
				(font
					(size 1.27 1.27)
					(thickness 0.15)
				)
				(justify left bottom)
				(hide yes)
			)
		)
		(property "Val" "100n"
			(at 20.955 196.85 90)
			(effects
				(font
					(size 1.27 1.27)
					(thickness 0.15)
				)
				(justify right)
			)
		)
		(property "License" "Apache-2.0"
			(at 41.91 177.8 0)
			(effects
				(font
					(size 1.27 1.27)
					(thickness 0.15)
				)
				(justify left bottom)
				(hide yes)
			)
		)
		(property "Author" "Antmicro"
			(at 44.45 177.8 0)
			(effects
				(font
					(size 1.27 1.27)
					(thickness 0.15)
				)
				(justify left bottom)
				(hide yes)
			)
		)
		(property "Voltage" "50V"
			(at 46.99 177.8 0)
			(effects
				(font
					(size 1.27 1.27)
				)
				(justify left bottom)
				(hide yes)
			)
		)
		(property "Dielectric" "X5R"
			(at 49.53 177.8 0)
			(effects
				(font
					(size 1.27 1.27)
				)
				(justify left bottom)
				(hide yes)
			)
		)
		(pin "1"
		)
		(pin "2"
		)
		(instances
			(project "sdi-mipi-video-converter"
				(path ""
					(reference "C1")
					(unit 1)
				)
			)
		)
	)
	(symbol
		(lib_id "antmicroResistors0402:R_15k_0402")
		(at 345.44 243.84 90)
		(unit 1)
		(exclude_from_sim no)
		(in_bom yes)
		(on_board yes)
		(dnp no)
		(fields_autoplaced yes)
		(property "Reference" "R36"
			(at 342.9 240.0299 90)
			(effects
				(font
					(size 1.27 1.27)
					(thickness 0.15)
				)
				(justify left)
			)
		)
		(property "Value" "R_15k_0402"
			(at 358.14 223.52 0)
			(effects
				(font
					(size 1.27 1.27)
					(thickness 0.15)
				)
				(justify left bottom)
				(hide yes)
			)
		)
		(property "Footprint" "antmicro-footprints:R_0402_1005Metric"
			(at 360.68 223.52 0)
			(effects
				(font
					(size 1.27 1.27)
					(thickness 0.15)
				)
				(justify left bottom)
				(hide yes)
			)
		)
		(property "Datasheet" "https://www.bourns.com/docs/product-datasheets/cr.pdf"
			(at 363.22 223.52 0)
			(effects
				(font
					(size 1.27 1.27)
					(thickness 0.15)
				)
				(justify left bottom)
				(hide yes)
			)
		)
		(property "Description" "SMD Chip Resistor, 15 kohm, ± 1%, 62.5 mW, 0402 [1005 Metric], Thick Film, General Purpose"
			(at 345.44 243.84 0)
			(effects
				(font
					(size 1.27 1.27)
				)
				(hide yes)
			)
		)
		(property "Manufacturer" "Bourns"
			(at 368.3 223.52 0)
			(effects
				(font
					(size 1.27 1.27)
					(thickness 0.15)
				)
				(justify left bottom)
				(hide yes)
			)
		)
		(property "MPN" "CR0402-FX-1502GLF"
			(at 365.76 223.52 0)
			(effects
				(font
					(size 1.27 1.27)
					(thickness 0.15)
				)
				(justify left bottom)
				(hide yes)
			)
		)
		(property "Val" "15k"
			(at 342.9 242.5699 90)
			(effects
				(font
					(size 1.27 1.27)
					(thickness 0.15)
				)
				(justify left)
			)
		)
		(property "License" "Apache-2.0"
			(at 370.84 223.52 0)
			(effects
				(font
					(size 1.27 1.27)
					(thickness 0.15)
				)
				(justify left bottom)
				(hide yes)
			)
		)
		(property "Author" "Antmicro"
			(at 373.38 223.52 0)
			(effects
				(font
					(size 1.27 1.27)
					(thickness 0.15)
				)
				(justify left bottom)
				(hide yes)
			)
		)
		(property "Tolerance" "1%"
			(at 355.6 223.52 0)
			(effects
				(font
					(size 1.27 1.27)
				)
				(justify left bottom)
				(hide yes)
			)
		)
		(pin "1"
		)
		(pin "2"
		)
		(instances
			(project "sdi-mipi-video-converter"
				(path ""
					(reference "R36")
					(unit 1)
				)
			)
		)
	)
	(symbol
		(lib_id "antmicroTestPoints:TP_0.75mm_SMD")
		(at 195.58 193.04 90)
		(unit 1)
		(exclude_from_sim no)
		(in_bom yes)
		(on_board yes)
		(dnp no)
		(fields_autoplaced yes)
		(property "Reference" "TP1"
			(at 198.12 189.865 90)
			(effects
				(font
					(size 1.27 1.27)
					(thickness 0.15)
				)
				(justify right)
			)
		)
		(property "Value" "TP_0.75mm_SMD"
			(at 203.2 175.26 0)
			(effects
				(font
					(size 1.27 1.27)
					(thickness 0.15)
				)
				(justify left bottom)
				(hide yes)
			)
		)
		(property "Footprint" "antmicro-footprints:TP_SMD_0.75mm"
			(at 205.74 175.26 0)
			(effects
				(font
					(size 1.27 1.27)
					(thickness 0.15)
				)
				(justify left bottom)
				(hide yes)
			)
		)
		(property "Datasheet" ""
			(at 208.28 175.26 0)
			(effects
				(font
					(size 1.27 1.27)
					(thickness 0.15)
				)
				(justify left bottom)
				(hide yes)
			)
		)
		(property "Description" "SMT test point"
			(at 195.58 193.04 0)
			(effects
				(font
					(size 1.27 1.27)
				)
				(hide yes)
			)
		)
		(property "MPN" ""
			(at 210.82 175.26 0)
			(effects
				(font
					(size 1.27 1.27)
					(thickness 0.15)
				)
				(justify left bottom)
				(hide yes)
			)
		)
		(property "Manufacturer" ""
			(at 213.36 175.26 0)
			(effects
				(font
					(size 1.27 1.27)
					(thickness 0.15)
				)
				(justify left bottom)
				(hide yes)
			)
		)
		(property "Author" "Antmicro"
			(at 215.9 175.26 0)
			(effects
				(font
					(size 1.27 1.27)
					(thickness 0.15)
				)
				(justify left bottom)
				(hide yes)
			)
		)
		(property "License" "Apache-2.0"
			(at 218.44 175.26 0)
			(effects
				(font
					(size 1.27 1.27)
					(thickness 0.15)
				)
				(justify left bottom)
				(hide yes)
			)
		)
		(pin "1"
		)
		(instances
			(project "sdi-mipi-video-converter"
				(path ""
					(reference "TP1")
					(unit 1)
				)
			)
		)
	)
	(symbol
		(lib_id "antmicropower:+1V5")
		(at 233.68 187.96 0)
		(unit 1)
		(exclude_from_sim no)
		(in_bom yes)
		(on_board yes)
		(dnp no)
		(fields_autoplaced yes)
		(property "Reference" "#PWR0228"
			(at 233.68 191.77 0)
			(effects
				(font
					(size 1.27 1.27)
				)
				(hide yes)
			)
		)
		(property "Value" "+1V5"
			(at 233.68 182.88 0)
			(effects
				(font
					(size 1.27 1.27)
				)
			)
		)
		(property "Footprint" ""
			(at 233.68 187.96 0)
			(effects
				(font
					(size 1.27 1.27)
				)
				(hide yes)
			)
		)
		(property "Datasheet" ""
			(at 233.68 187.96 0)
			(effects
				(font
					(size 1.27 1.27)
				)
				(hide yes)
			)
		)
		(property "Description" ""
			(at 233.68 187.96 0)
			(effects
				(font
					(size 1.27 1.27)
				)
				(hide yes)
			)
		)
		(pin "1"
		)
		(instances
			(project "sdi-mipi-video-converter"
				(path ""
					(reference "#PWR0228")
					(unit 1)
				)
			)
		)
	)
	(symbol
		(lib_id "antmicroResistors0402:R_10k_0402")
		(at 46.99 85.09 90)
		(unit 1)
		(exclude_from_sim no)
		(in_bom yes)
		(on_board yes)
		(dnp no)
		(fields_autoplaced yes)
		(property "Reference" "R6"
			(at 49.53 81.2799 90)
			(effects
				(font
					(size 1.27 1.27)
					(thickness 0.15)
				)
				(justify right)
			)
		)
		(property "Value" "R_10k_0402"
			(at 59.69 64.77 0)
			(effects
				(font
					(size 1.27 1.27)
					(thickness 0.15)
				)
				(justify left bottom)
				(hide yes)
			)
		)
		(property "Footprint" "antmicro-footprints:R_0402_1005Metric"
			(at 62.23 64.77 0)
			(effects
				(font
					(size 1.27 1.27)
					(thickness 0.15)
				)
				(justify left bottom)
				(hide yes)
			)
		)
		(property "Datasheet" "https://www.bourns.com/docs/product-datasheets/cr.pdf"
			(at 64.77 64.77 0)
			(effects
				(font
					(size 1.27 1.27)
					(thickness 0.15)
				)
				(justify left bottom)
				(hide yes)
			)
		)
		(property "Description" "SMD Chip Resistor, 10 kohm, ± 1%, 62.5 mW, 0402 [1005 Metric], Thick Film, General Purpose"
			(at 46.99 85.09 0)
			(effects
				(font
					(size 1.27 1.27)
				)
				(hide yes)
			)
		)
		(property "Manufacturer" "Bourns"
			(at 69.85 64.77 0)
			(effects
				(font
					(size 1.27 1.27)
					(thickness 0.15)
				)
				(justify left bottom)
				(hide yes)
			)
		)
		(property "MPN" "CR0402-FX-1002GLF"
			(at 67.31 64.77 0)
			(effects
				(font
					(size 1.27 1.27)
					(thickness 0.15)
				)
				(justify left bottom)
				(hide yes)
			)
		)
		(property "Val" "10k"
			(at 49.53 83.8199 90)
			(effects
				(font
					(size 1.27 1.27)
					(thickness 0.15)
				)
				(justify right)
			)
		)
		(property "License" "Apache-2.0"
			(at 72.39 64.77 0)
			(effects
				(font
					(size 1.27 1.27)
					(thickness 0.15)
				)
				(justify left bottom)
				(hide yes)
			)
		)
		(property "Author" "Antmicro"
			(at 74.93 64.77 0)
			(effects
				(font
					(size 1.27 1.27)
					(thickness 0.15)
				)
				(justify left bottom)
				(hide yes)
			)
		)
		(property "Tolerance" "1%"
			(at 57.15 64.77 0)
			(effects
				(font
					(size 1.27 1.27)
				)
				(justify left bottom)
				(hide yes)
			)
		)
		(pin "1"
		)
		(pin "2"
		)
		(instances
			(project "sdi-mipi-video-converter"
				(path ""
					(reference "R6")
					(unit 1)
				)
			)
		)
	)
	(symbol
		(lib_id "antmicroCapacitors0603:C_10u_0603")
		(at 269.24 109.22 270)
		(unit 1)
		(exclude_from_sim no)
		(in_bom yes)
		(on_board yes)
		(dnp no)
		(fields_autoplaced yes)
		(property "Reference" "C12"
			(at 266.7 110.4962 90)
			(effects
				(font
					(size 1.27 1.27)
					(thickness 0.15)
				)
				(justify right)
			)
		)
		(property "Value" "C_10u_0603"
			(at 259.08 129.54 0)
			(effects
				(font
					(size 1.27 1.27)
					(thickness 0.15)
				)
				(justify left bottom)
				(hide yes)
			)
		)
		(property "Footprint" "antmicro-footprints:C_0603_1608Metric"
			(at 256.54 129.54 0)
			(effects
				(font
					(size 1.27 1.27)
					(thickness 0.15)
				)
				(justify left bottom)
				(hide yes)
			)
		)
		(property "Datasheet" "https://www.murata.com/products/productdetail?partno=GRM188R61A106KE69%23"
			(at 254 129.54 0)
			(effects
				(font
					(size 1.27 1.27)
					(thickness 0.15)
				)
				(justify left bottom)
				(hide yes)
			)
		)
		(property "Description" "SMD Multilayer Ceramic Capacitor, 10 µF, 10 V, 0603 [1608 Metric], ± 10%, X5R, GRM Series"
			(at 269.24 109.22 0)
			(effects
				(font
					(size 1.27 1.27)
				)
				(hide yes)
			)
		)
		(property "Manufacturer" "Murata"
			(at 248.92 129.54 0)
			(effects
				(font
					(size 1.27 1.27)
					(thickness 0.15)
				)
				(justify left bottom)
				(hide yes)
			)
		)
		(property "MPN" "GRM188R61A106KE69D"
			(at 251.46 129.54 0)
			(effects
				(font
					(size 1.27 1.27)
					(thickness 0.15)
				)
				(justify left bottom)
				(hide yes)
			)
		)
		(property "Val" "10u"
			(at 266.7 113.0362 90)
			(effects
				(font
					(size 1.27 1.27)
					(thickness 0.15)
				)
				(justify right)
			)
		)
		(property "License" "Apache-2.0"
			(at 246.38 129.54 0)
			(effects
				(font
					(size 1.27 1.27)
					(thickness 0.15)
				)
				(justify left bottom)
				(hide yes)
			)
		)
		(property "Author" "Antmicro"
			(at 243.84 129.54 0)
			(effects
				(font
					(size 1.27 1.27)
					(thickness 0.15)
				)
				(justify left bottom)
				(hide yes)
			)
		)
		(property "Voltage" ""
			(at 241.3 129.54 0)
			(effects
				(font
					(size 1.27 1.27)
				)
				(justify left bottom)
				(hide yes)
			)
		)
		(property "Dielectric" "template_dielectric"
			(at 238.76 129.54 0)
			(effects
				(font
					(size 1.27 1.27)
				)
				(justify left bottom)
				(hide yes)
			)
		)
		(pin "1"
		)
		(pin "2"
		)
		(instances
			(project "sdi-mipi-video-converter"
				(path ""
					(reference "C12")
					(unit 1)
				)
			)
		)
	)
	(symbol
		(lib_id "antmicroResistors0402:R_10k_0402")
		(at 91.44 60.96 90)
		(unit 1)
		(exclude_from_sim no)
		(in_bom yes)
		(on_board yes)
		(dnp no)
		(fields_autoplaced yes)
		(property "Reference" "R99"
			(at 93.98 57.1499 90)
			(effects
				(font
					(size 1.27 1.27)
					(thickness 0.15)
				)
				(justify right)
			)
		)
		(property "Value" "R_10k_0402"
			(at 104.14 40.64 0)
			(effects
				(font
					(size 1.27 1.27)
					(thickness 0.15)
				)
				(justify left bottom)
				(hide yes)
			)
		)
		(property "Footprint" "antmicro-footprints:R_0402_1005Metric"
			(at 106.68 40.64 0)
			(effects
				(font
					(size 1.27 1.27)
					(thickness 0.15)
				)
				(justify left bottom)
				(hide yes)
			)
		)
		(property "Datasheet" "https://www.bourns.com/docs/product-datasheets/cr.pdf"
			(at 109.22 40.64 0)
			(effects
				(font
					(size 1.27 1.27)
					(thickness 0.15)
				)
				(justify left bottom)
				(hide yes)
			)
		)
		(property "Description" "SMD Chip Resistor, 10 kohm, ± 1%, 62.5 mW, 0402 [1005 Metric], Thick Film, General Purpose"
			(at 91.44 60.96 0)
			(effects
				(font
					(size 1.27 1.27)
				)
				(hide yes)
			)
		)
		(property "Manufacturer" "Bourns"
			(at 114.3 40.64 0)
			(effects
				(font
					(size 1.27 1.27)
					(thickness 0.15)
				)
				(justify left bottom)
				(hide yes)
			)
		)
		(property "MPN" "CR0402-FX-1002GLF"
			(at 111.76 40.64 0)
			(effects
				(font
					(size 1.27 1.27)
					(thickness 0.15)
				)
				(justify left bottom)
				(hide yes)
			)
		)
		(property "Val" "10k"
			(at 93.98 59.6899 90)
			(effects
				(font
					(size 1.27 1.27)
					(thickness 0.15)
				)
				(justify right)
			)
		)
		(property "License" "Apache-2.0"
			(at 116.84 40.64 0)
			(effects
				(font
					(size 1.27 1.27)
					(thickness 0.15)
				)
				(justify left bottom)
				(hide yes)
			)
		)
		(property "Author" "Antmicro"
			(at 119.38 40.64 0)
			(effects
				(font
					(size 1.27 1.27)
					(thickness 0.15)
				)
				(justify left bottom)
				(hide yes)
			)
		)
		(property "Tolerance" "1%"
			(at 101.6 40.64 0)
			(effects
				(font
					(size 1.27 1.27)
				)
				(justify left bottom)
				(hide yes)
			)
		)
		(pin "1"
		)
		(pin "2"
		)
		(instances
			(project "sdi-mipi-video-converter"
				(path ""
					(reference "R99")
					(unit 1)
				)
			)
		)
	)
	(symbol
		(lib_id "antmicroCapacitors0402:C_100n_0402")
		(at 60.96 199.39 90)
		(unit 1)
		(exclude_from_sim no)
		(in_bom yes)
		(on_board yes)
		(dnp no)
		(fields_autoplaced yes)
		(property "Reference" "C2"
			(at 63.5 195.5735 90)
			(effects
				(font
					(size 1.27 1.27)
					(thickness 0.15)
				)
				(justify right)
			)
		)
		(property "Value" "C_100n_0402"
			(at 71.12 179.07 0)
			(effects
				(font
					(size 1.27 1.27)
					(thickness 0.15)
				)
				(justify left bottom)
				(hide yes)
			)
		)
		(property "Footprint" "antmicro-footprints:C_0402_1005Metric"
			(at 73.66 179.07 0)
			(effects
				(font
					(size 1.27 1.27)
					(thickness 0.15)
				)
				(justify left bottom)
				(hide yes)
			)
		)
		(property "Datasheet" "https://www.murata.com/products/productdetail?partno=GRM155R61H104KE14%23"
			(at 76.2 179.07 0)
			(effects
				(font
					(size 1.27 1.27)
					(thickness 0.15)
				)
				(justify left bottom)
				(hide yes)
			)
		)
		(property "Description" "SMD Multilayer Ceramic Capacitor, 0.1 µF, 50 V, 0402 [1005 Metric], ± 10%, X5R, GRM Series"
			(at 60.96 199.39 0)
			(effects
				(font
					(size 1.27 1.27)
				)
				(hide yes)
			)
		)
		(property "Manufacturer" "Murata"
			(at 81.28 179.07 0)
			(effects
				(font
					(size 1.27 1.27)
					(thickness 0.15)
				)
				(justify left bottom)
				(hide yes)
			)
		)
		(property "MPN" "GRM155R61H104KE14D"
			(at 78.74 179.07 0)
			(effects
				(font
					(size 1.27 1.27)
					(thickness 0.15)
				)
				(justify left bottom)
				(hide yes)
			)
		)
		(property "Val" "100n"
			(at 63.5 198.1135 90)
			(effects
				(font
					(size 1.27 1.27)
					(thickness 0.15)
				)
				(justify right)
			)
		)
		(property "License" "Apache-2.0"
			(at 83.82 179.07 0)
			(effects
				(font
					(size 1.27 1.27)
					(thickness 0.15)
				)
				(justify left bottom)
				(hide yes)
			)
		)
		(property "Author" "Antmicro"
			(at 86.36 179.07 0)
			(effects
				(font
					(size 1.27 1.27)
					(thickness 0.15)
				)
				(justify left bottom)
				(hide yes)
			)
		)
		(property "Voltage" "50V"
			(at 88.9 179.07 0)
			(effects
				(font
					(size 1.27 1.27)
				)
				(justify left bottom)
				(hide yes)
			)
		)
		(property "Dielectric" "X5R"
			(at 91.44 179.07 0)
			(effects
				(font
					(size 1.27 1.27)
				)
				(justify left bottom)
				(hide yes)
			)
		)
		(pin "1"
		)
		(pin "2"
		)
		(instances
			(project "sdi-mipi-video-converter"
				(path ""
					(reference "C2")
					(unit 1)
				)
			)
		)
	)
	(symbol
		(lib_id "antmicropower:+5V")
		(at 101.6 185.42 0)
		(unit 1)
		(exclude_from_sim no)
		(in_bom yes)
		(on_board yes)
		(dnp no)
		(fields_autoplaced yes)
		(property "Reference" "#PWR07"
			(at 116.84 187.96 0)
			(effects
				(font
					(size 1.27 1.27)
					(thickness 0.15)
				)
				(justify left bottom)
				(hide yes)
			)
		)
		(property "Value" "+5V"
			(at 101.6 180.34 0)
			(effects
				(font
					(size 1.27 1.27)
					(thickness 0.15)
				)
			)
		)
		(property "Footprint" ""
			(at 116.84 193.04 0)
			(effects
				(font
					(size 1.27 1.27)
					(thickness 0.15)
				)
				(justify left bottom)
				(hide yes)
			)
		)
		(property "Datasheet" ""
			(at 116.84 195.58 0)
			(effects
				(font
					(size 1.27 1.27)
					(thickness 0.15)
				)
				(justify left bottom)
				(hide yes)
			)
		)
		(property "Description" ""
			(at 101.6 185.42 0)
			(effects
				(font
					(size 1.27 1.27)
				)
				(hide yes)
			)
		)
		(property "Author" "Antmicro"
			(at 116.84 193.04 0)
			(effects
				(font
					(size 1.27 1.27)
					(thickness 0.15)
				)
				(justify left bottom)
				(hide yes)
			)
		)
		(property "License" "Apache-2.0"
			(at 116.84 195.58 0)
			(effects
				(font
					(size 1.27 1.27)
					(thickness 0.15)
				)
				(justify left bottom)
				(hide yes)
			)
		)
		(pin "1"
		)
		(instances
			(project "sdi-mipi-video-converter"
				(path ""
					(reference "#PWR07")
					(unit 1)
				)
			)
		)
	)
	(symbol
		(lib_id "antmicroTestPoints:TP_0.75mm_SMD")
		(at 284.48 110.49 180)
		(unit 1)
		(exclude_from_sim no)
		(in_bom yes)
		(on_board yes)
		(dnp no)
		(fields_autoplaced yes)
		(property "Reference" "TP11"
			(at 281.305 106.68 0)
			(effects
				(font
					(size 1.27 1.27)
					(thickness 0.15)
				)
			)
		)
		(property "Value" "TP_0.75mm_SMD"
			(at 266.7 102.87 0)
			(effects
				(font
					(size 1.27 1.27)
					(thickness 0.15)
				)
				(justify left bottom)
				(hide yes)
			)
		)
		(property "Footprint" "antmicro-footprints:TP_SMD_0.75mm"
			(at 266.7 100.33 0)
			(effects
				(font
					(size 1.27 1.27)
					(thickness 0.15)
				)
				(justify left bottom)
				(hide yes)
			)
		)
		(property "Datasheet" ""
			(at 266.7 97.79 0)
			(effects
				(font
					(size 1.27 1.27)
					(thickness 0.15)
				)
				(justify left bottom)
				(hide yes)
			)
		)
		(property "Description" "SMT test point"
			(at 284.48 110.49 0)
			(effects
				(font
					(size 1.27 1.27)
				)
				(hide yes)
			)
		)
		(property "MPN" ""
			(at 266.7 95.25 0)
			(effects
				(font
					(size 1.27 1.27)
					(thickness 0.15)
				)
				(justify left bottom)
				(hide yes)
			)
		)
		(property "Manufacturer" ""
			(at 266.7 92.71 0)
			(effects
				(font
					(size 1.27 1.27)
					(thickness 0.15)
				)
				(justify left bottom)
				(hide yes)
			)
		)
		(property "Author" "Antmicro"
			(at 266.7 90.17 0)
			(effects
				(font
					(size 1.27 1.27)
					(thickness 0.15)
				)
				(justify left bottom)
				(hide yes)
			)
		)
		(property "License" "Apache-2.0"
			(at 266.7 87.63 0)
			(effects
				(font
					(size 1.27 1.27)
					(thickness 0.15)
				)
				(justify left bottom)
				(hide yes)
			)
		)
		(pin "1"
		)
		(instances
			(project "sdi-mipi-video-converter"
				(path ""
					(reference "TP11")
					(unit 1)
				)
			)
		)
	)
	(symbol
		(lib_id "antmicroResistorsmisc:R_0R_0805")
		(at 262.89 39.37 0)
		(unit 1)
		(exclude_from_sim no)
		(in_bom yes)
		(on_board yes)
		(dnp no)
		(fields_autoplaced yes)
		(property "Reference" "R17"
			(at 265.43 33.02 0)
			(effects
				(font
					(size 1.27 1.27)
					(thickness 0.15)
				)
			)
		)
		(property "Value" "R_0R_0805"
			(at 283.21 52.07 0)
			(effects
				(font
					(size 1.27 1.27)
					(thickness 0.15)
				)
				(justify left bottom)
				(hide yes)
			)
		)
		(property "Footprint" "antmicro-footprints:R_0805_2012Metric"
			(at 283.21 54.61 0)
			(effects
				(font
					(size 1.27 1.27)
					(thickness 0.15)
				)
				(justify left bottom)
				(hide yes)
			)
		)
		(property "Datasheet" "https://www.vishay.com/docs/20035/dcrcwe3.pdf"
			(at 283.21 57.15 0)
			(effects
				(font
					(size 1.27 1.27)
					(thickness 0.15)
				)
				(justify left bottom)
				(hide yes)
			)
		)
		(property "Description" "Zero Ohm Resistor, Jumper, 0805 [2012 Metric], Thick Film, 125 mW, 2.5 A, Surface Mount Device"
			(at 262.89 39.37 0)
			(effects
				(font
					(size 1.27 1.27)
				)
				(hide yes)
			)
		)
		(property "Manufacturer" "Vishay"
			(at 283.21 62.23 0)
			(effects
				(font
					(size 1.27 1.27)
					(thickness 0.15)
				)
				(justify left bottom)
				(hide yes)
			)
		)
		(property "MPN" "CRCW08050000Z0EA"
			(at 283.21 59.69 0)
			(effects
				(font
					(size 1.27 1.27)
					(thickness 0.15)
				)
				(justify left bottom)
				(hide yes)
			)
		)
		(property "Val" "0R"
			(at 265.43 35.56 0)
			(effects
				(font
					(size 1.27 1.27)
					(thickness 0.15)
				)
			)
		)
		(property "License" "Apache-2.0"
			(at 283.21 64.77 0)
			(effects
				(font
					(size 1.27 1.27)
					(thickness 0.15)
				)
				(justify left bottom)
				(hide yes)
			)
		)
		(property "Author" "Antmicro"
			(at 283.21 67.31 0)
			(effects
				(font
					(size 1.27 1.27)
					(thickness 0.15)
				)
				(justify left bottom)
				(hide yes)
			)
		)
		(property "Tolerance" "~"
			(at 283.21 49.53 0)
			(effects
				(font
					(size 1.27 1.27)
				)
				(justify left bottom)
				(hide yes)
			)
		)
		(property "Current" "2.5A"
			(at 283.21 69.85 0)
			(effects
				(font
					(size 1.27 1.27)
					(thickness 0.15)
				)
				(justify left bottom)
				(hide yes)
			)
		)
		(pin "1"
		)
		(pin "2"
		)
		(instances
			(project "sdi-mipi-video-converter"
				(path ""
					(reference "R17")
					(unit 1)
				)
			)
		)
	)
	(symbol
		(lib_id "antmicropower:GND")
		(at 336.55 124.46 0)
		(unit 1)
		(exclude_from_sim no)
		(in_bom yes)
		(on_board yes)
		(dnp no)
		(fields_autoplaced yes)
		(property "Reference" "#PWR054"
			(at 345.44 127 0)
			(effects
				(font
					(size 1.27 1.27)
					(thickness 0.15)
				)
				(justify left bottom)
				(hide yes)
			)
		)
		(property "Value" "GND"
			(at 336.55 129.54 0)
			(effects
				(font
					(size 1.27 1.27)
					(thickness 0.15)
				)
			)
		)
		(property "Footprint" ""
			(at 345.44 132.08 0)
			(effects
				(font
					(size 1.27 1.27)
					(thickness 0.15)
				)
				(justify left bottom)
				(hide yes)
			)
		)
		(property "Datasheet" ""
			(at 345.44 137.16 0)
			(effects
				(font
					(size 1.27 1.27)
					(thickness 0.15)
				)
				(justify left bottom)
				(hide yes)
			)
		)
		(property "Description" ""
			(at 336.55 124.46 0)
			(effects
				(font
					(size 1.27 1.27)
				)
				(hide yes)
			)
		)
		(property "Author" "Antmicro"
			(at 345.44 132.08 0)
			(effects
				(font
					(size 1.27 1.27)
					(thickness 0.15)
				)
				(justify left bottom)
				(hide yes)
			)
		)
		(property "License" "Apache-2.0"
			(at 345.44 134.62 0)
			(effects
				(font
					(size 1.27 1.27)
					(thickness 0.15)
				)
				(justify left bottom)
				(hide yes)
			)
		)
		(pin "1"
		)
		(instances
			(project "sdi-mipi-video-converter"
				(path ""
					(reference "#PWR054")
					(unit 1)
				)
			)
		)
	)
	(symbol
		(lib_id "antmicroCapacitors0603:C_22u_0603")
		(at 367.03 52.07 90)
		(unit 1)
		(exclude_from_sim no)
		(in_bom yes)
		(on_board yes)
		(dnp no)
		(fields_autoplaced yes)
		(property "Reference" "C25"
			(at 369.57 48.2535 90)
			(effects
				(font
					(size 1.27 1.27)
					(thickness 0.15)
				)
				(justify right)
			)
		)
		(property "Value" "C_22u_0603"
			(at 377.19 31.75 0)
			(effects
				(font
					(size 1.27 1.27)
					(thickness 0.15)
				)
				(justify left bottom)
				(hide yes)
			)
		)
		(property "Footprint" "antmicro-footprints:C_0603_1608Metric"
			(at 379.73 31.75 0)
			(effects
				(font
					(size 1.27 1.27)
					(thickness 0.15)
				)
				(justify left bottom)
				(hide yes)
			)
		)
		(property "Datasheet" "https://www.murata.com/products/productdetail?partno=GRM188R60J226MEA0%23"
			(at 382.27 31.75 0)
			(effects
				(font
					(size 1.27 1.27)
					(thickness 0.15)
				)
				(justify left bottom)
				(hide yes)
			)
		)
		(property "Description" "SMD Multilayer Ceramic Capacitor, 22 µF, 6.3 V, 0603 [1608 Metric], ± 20%, X5R, GRM Series"
			(at 367.03 52.07 0)
			(effects
				(font
					(size 1.27 1.27)
				)
				(hide yes)
			)
		)
		(property "Manufacturer" "Murata"
			(at 387.35 31.75 0)
			(effects
				(font
					(size 1.27 1.27)
					(thickness 0.15)
				)
				(justify left bottom)
				(hide yes)
			)
		)
		(property "MPN" "GRM188R60J226MEA0D"
			(at 384.81 31.75 0)
			(effects
				(font
					(size 1.27 1.27)
					(thickness 0.15)
				)
				(justify left bottom)
				(hide yes)
			)
		)
		(property "Val" "22u"
			(at 369.57 50.7935 90)
			(effects
				(font
					(size 1.27 1.27)
					(thickness 0.15)
				)
				(justify right)
			)
		)
		(property "License" "Apache-2.0"
			(at 389.89 31.75 0)
			(effects
				(font
					(size 1.27 1.27)
					(thickness 0.15)
				)
				(justify left bottom)
				(hide yes)
			)
		)
		(property "Author" "Antmicro"
			(at 392.43 31.75 0)
			(effects
				(font
					(size 1.27 1.27)
					(thickness 0.15)
				)
				(justify left bottom)
				(hide yes)
			)
		)
		(property "Voltage" ""
			(at 394.97 31.75 0)
			(effects
				(font
					(size 1.27 1.27)
				)
				(justify left bottom)
				(hide yes)
			)
		)
		(property "Dielectric" ""
			(at 397.51 31.75 0)
			(effects
				(font
					(size 1.27 1.27)
				)
				(justify left bottom)
				(hide yes)
			)
		)
		(pin "1"
		)
		(pin "2"
		)
		(instances
			(project "sdi-mipi-video-converter"
				(path ""
					(reference "C25")
					(unit 1)
				)
			)
		)
	)
	(symbol
		(lib_id "antmicroResistorsmisc:R_0R_0805")
		(at 392.43 72.39 0)
		(unit 1)
		(exclude_from_sim no)
		(in_bom yes)
		(on_board yes)
		(dnp no)
		(fields_autoplaced yes)
		(property "Reference" "R41"
			(at 394.97 66.04 0)
			(effects
				(font
					(size 1.27 1.27)
					(thickness 0.15)
				)
			)
		)
		(property "Value" "R_0R_0805"
			(at 412.75 85.09 0)
			(effects
				(font
					(size 1.27 1.27)
					(thickness 0.15)
				)
				(justify left bottom)
				(hide yes)
			)
		)
		(property "Footprint" "antmicro-footprints:R_0805_2012Metric"
			(at 412.75 87.63 0)
			(effects
				(font
					(size 1.27 1.27)
					(thickness 0.15)
				)
				(justify left bottom)
				(hide yes)
			)
		)
		(property "Datasheet" "https://www.vishay.com/docs/20035/dcrcwe3.pdf"
			(at 412.75 90.17 0)
			(effects
				(font
					(size 1.27 1.27)
					(thickness 0.15)
				)
				(justify left bottom)
				(hide yes)
			)
		)
		(property "Description" "Zero Ohm Resistor, Jumper, 0805 [2012 Metric], Thick Film, 125 mW, 2.5 A, Surface Mount Device"
			(at 392.43 72.39 0)
			(effects
				(font
					(size 1.27 1.27)
				)
				(hide yes)
			)
		)
		(property "Manufacturer" "Vishay"
			(at 412.75 95.25 0)
			(effects
				(font
					(size 1.27 1.27)
					(thickness 0.15)
				)
				(justify left bottom)
				(hide yes)
			)
		)
		(property "MPN" "CRCW08050000Z0EA"
			(at 412.75 92.71 0)
			(effects
				(font
					(size 1.27 1.27)
					(thickness 0.15)
				)
				(justify left bottom)
				(hide yes)
			)
		)
		(property "Val" "0R"
			(at 394.97 68.58 0)
			(effects
				(font
					(size 1.27 1.27)
					(thickness 0.15)
				)
			)
		)
		(property "License" "Apache-2.0"
			(at 412.75 97.79 0)
			(effects
				(font
					(size 1.27 1.27)
					(thickness 0.15)
				)
				(justify left bottom)
				(hide yes)
			)
		)
		(property "Author" "Antmicro"
			(at 412.75 100.33 0)
			(effects
				(font
					(size 1.27 1.27)
					(thickness 0.15)
				)
				(justify left bottom)
				(hide yes)
			)
		)
		(property "Tolerance" "~"
			(at 412.75 82.55 0)
			(effects
				(font
					(size 1.27 1.27)
				)
				(justify left bottom)
				(hide yes)
			)
		)
		(property "Current" "2.5A"
			(at 412.75 102.87 0)
			(effects
				(font
					(size 1.27 1.27)
					(thickness 0.15)
				)
				(justify left bottom)
				(hide yes)
			)
		)
		(pin "1"
		)
		(pin "2"
		)
		(instances
			(project "sdi-mipi-video-converter"
				(path ""
					(reference "R41")
					(unit 1)
				)
			)
		)
	)
	(symbol
		(lib_id "antmicroResistorsmisc:R_0R_1206")
		(at 115.57 77.47 0)
		(unit 1)
		(exclude_from_sim no)
		(in_bom yes)
		(on_board yes)
		(dnp no)
		(fields_autoplaced yes)
		(property "Reference" "R13"
			(at 118.11 71.12 0)
			(effects
				(font
					(size 1.27 1.27)
					(thickness 0.15)
				)
			)
		)
		(property "Value" "R_0R_1206"
			(at 135.89 90.17 0)
			(effects
				(font
					(size 1.27 1.27)
					(thickness 0.15)
				)
				(justify left bottom)
				(hide yes)
			)
		)
		(property "Footprint" "antmicro-footprints:R_1206_3216Metric"
			(at 135.89 92.71 0)
			(effects
				(font
					(size 1.27 1.27)
					(thickness 0.15)
				)
				(justify left bottom)
				(hide yes)
			)
		)
		(property "Datasheet" "https://www.farnell.com/datasheets/2860635.pdf"
			(at 135.89 95.25 0)
			(effects
				(font
					(size 1.27 1.27)
					(thickness 0.15)
				)
				(justify left bottom)
				(hide yes)
			)
		)
		(property "Description" "Zero Ohm Resistor, Jumper, 1206 [3216 Metric], Thick Film, 250 mW, 2 A, Surface Mount Device"
			(at 115.57 77.47 0)
			(effects
				(font
					(size 1.27 1.27)
				)
				(hide yes)
			)
		)
		(property "Manufacturer" "Multicomp Pro"
			(at 135.89 100.33 0)
			(effects
				(font
					(size 1.27 1.27)
					(thickness 0.15)
				)
				(justify left bottom)
				(hide yes)
			)
		)
		(property "MPN" "MCMR12X000_PTL"
			(at 135.89 97.79 0)
			(effects
				(font
					(size 1.27 1.27)
					(thickness 0.15)
				)
				(justify left bottom)
				(hide yes)
			)
		)
		(property "Val" "0R"
			(at 118.11 73.66 0)
			(effects
				(font
					(size 1.27 1.27)
					(thickness 0.15)
				)
			)
		)
		(property "License" "Apache-2.0"
			(at 135.89 102.87 0)
			(effects
				(font
					(size 1.27 1.27)
					(thickness 0.15)
				)
				(justify left bottom)
				(hide yes)
			)
		)
		(property "Author" "Antmicro"
			(at 135.89 105.41 0)
			(effects
				(font
					(size 1.27 1.27)
					(thickness 0.15)
				)
				(justify left bottom)
				(hide yes)
			)
		)
		(property "Tolerance" "~"
			(at 135.89 87.63 0)
			(effects
				(font
					(size 1.27 1.27)
				)
				(justify left bottom)
				(hide yes)
			)
		)
		(property "Current" "2A"
			(at 135.89 107.95 0)
			(effects
				(font
					(size 1.27 1.27)
					(thickness 0.15)
				)
				(justify left bottom)
				(hide yes)
			)
		)
		(pin "1"
		)
		(pin "2"
		)
		(instances
			(project "sdi-mipi-video-converter"
				(path ""
					(reference "R13")
					(unit 1)
				)
			)
		)
	)
	(symbol
		(lib_id "antmicroTransistorsFETsMOSFETsSingle:AO3401A")
		(at 91.44 34.29 90)
		(unit 1)
		(exclude_from_sim no)
		(in_bom yes)
		(on_board yes)
		(dnp no)
		(fields_autoplaced yes)
		(property "Reference" "Q3"
			(at 88.9 19.05 90)
			(effects
				(font
					(size 1.27 1.27)
					(thickness 0.15)
				)
			)
		)
		(property "Value" "AO3401A"
			(at 88.9 21.59 90)
			(effects
				(font
					(size 1.27 1.27)
					(thickness 0.15)
				)
			)
		)
		(property "Footprint" "antmicro-footprints:SOT-23-3"
			(at 102.87 11.43 0)
			(effects
				(font
					(size 1.27 1.27)
					(thickness 0.15)
				)
				(justify left bottom)
				(hide yes)
			)
		)
		(property "Datasheet" "http://aosmd.com/res/data_sheets/AO3401A.pdf"
			(at 105.41 11.43 0)
			(effects
				(font
					(size 1.27 1.27)
					(thickness 0.15)
				)
				(justify left bottom)
				(hide yes)
			)
		)
		(property "Description" "Power MOSFET, P Channel, 30 V, 4 A, 0.07 ohm, SOT-23, Surface Mount"
			(at 91.44 34.29 0)
			(effects
				(font
					(size 1.27 1.27)
				)
				(hide yes)
			)
		)
		(property "MPN" "AO3401A"
			(at 107.95 11.43 0)
			(effects
				(font
					(size 1.27 1.27)
					(thickness 0.15)
				)
				(justify left bottom)
				(hide yes)
			)
		)
		(property "Manufacturer" "AOSMD"
			(at 110.49 11.43 0)
			(effects
				(font
					(size 1.27 1.27)
					(thickness 0.15)
				)
				(justify left bottom)
				(hide yes)
			)
		)
		(property "Author" "Antmicro"
			(at 113.03 11.43 0)
			(effects
				(font
					(size 1.27 1.27)
					(thickness 0.15)
				)
				(justify left bottom)
				(hide yes)
			)
		)
		(property "License" "Apache-2.0"
			(at 115.57 11.43 0)
			(effects
				(font
					(size 1.27 1.27)
					(thickness 0.15)
				)
				(justify left bottom)
				(hide yes)
			)
		)
		(pin "1"
		)
		(pin "2"
		)
		(pin "3"
		)
		(instances
			(project "sdi-mipi-video-converter"
				(path ""
					(reference "Q3")
					(unit 1)
				)
			)
		)
	)
	(symbol
		(lib_id "antmicropower:GND")
		(at 40.64 148.59 0)
		(unit 1)
		(exclude_from_sim no)
		(in_bom yes)
		(on_board yes)
		(dnp no)
		(fields_autoplaced yes)
		(property "Reference" "#PWR0221"
			(at 49.53 151.13 0)
			(effects
				(font
					(size 1.27 1.27)
					(thickness 0.15)
				)
				(justify left bottom)
				(hide yes)
			)
		)
		(property "Value" "GND"
			(at 40.64 153.67 0)
			(effects
				(font
					(size 1.27 1.27)
					(thickness 0.15)
				)
			)
		)
		(property "Footprint" ""
			(at 49.53 156.21 0)
			(effects
				(font
					(size 1.27 1.27)
					(thickness 0.15)
				)
				(justify left bottom)
				(hide yes)
			)
		)
		(property "Datasheet" ""
			(at 49.53 161.29 0)
			(effects
				(font
					(size 1.27 1.27)
					(thickness 0.15)
				)
				(justify left bottom)
				(hide yes)
			)
		)
		(property "Description" ""
			(at 40.64 148.59 0)
			(effects
				(font
					(size 1.27 1.27)
				)
				(hide yes)
			)
		)
		(property "Author" "Antmicro"
			(at 49.53 156.21 0)
			(effects
				(font
					(size 1.27 1.27)
					(thickness 0.15)
				)
				(justify left bottom)
				(hide yes)
			)
		)
		(property "License" "Apache-2.0"
			(at 49.53 158.75 0)
			(effects
				(font
					(size 1.27 1.27)
					(thickness 0.15)
				)
				(justify left bottom)
				(hide yes)
			)
		)
		(pin "1"
		)
		(instances
			(project "sdi-mipi-video-converter"
				(path ""
					(reference "#PWR0221")
					(unit 1)
				)
			)
		)
	)
	(symbol
		(lib_id "antmicroResistors0402:R_12k_0402")
		(at 345.44 199.39 90)
		(unit 1)
		(exclude_from_sim no)
		(in_bom yes)
		(on_board yes)
		(dnp no)
		(fields_autoplaced yes)
		(property "Reference" "R33"
			(at 347.98 195.5799 90)
			(effects
				(font
					(size 1.27 1.27)
					(thickness 0.15)
				)
				(justify right)
			)
		)
		(property "Value" "R_12k_0402"
			(at 358.14 179.07 0)
			(effects
				(font
					(size 1.27 1.27)
					(thickness 0.15)
				)
				(justify left bottom)
				(hide yes)
			)
		)
		(property "Footprint" "antmicro-footprints:R_0402_1005Metric"
			(at 360.68 179.07 0)
			(effects
				(font
					(size 1.27 1.27)
					(thickness 0.15)
				)
				(justify left bottom)
				(hide yes)
			)
		)
		(property "Datasheet" "https://www.bourns.com/docs/product-datasheets/cr.pdf"
			(at 363.22 179.07 0)
			(effects
				(font
					(size 1.27 1.27)
					(thickness 0.15)
				)
				(justify left bottom)
				(hide yes)
			)
		)
		(property "Description" "SMD Chip Resistor, 12 kohm, ± 1%, 62.5 mW, 0402 [1005 Metric], Thick Film, General Purpose"
			(at 345.44 199.39 0)
			(effects
				(font
					(size 1.27 1.27)
				)
				(hide yes)
			)
		)
		(property "Manufacturer" "Bourns"
			(at 368.3 179.07 0)
			(effects
				(font
					(size 1.27 1.27)
					(thickness 0.15)
				)
				(justify left bottom)
				(hide yes)
			)
		)
		(property "MPN" "CR0402-FX-1202GLF"
			(at 365.76 179.07 0)
			(effects
				(font
					(size 1.27 1.27)
					(thickness 0.15)
				)
				(justify left bottom)
				(hide yes)
			)
		)
		(property "Val" "12k"
			(at 347.98 198.1199 90)
			(effects
				(font
					(size 1.27 1.27)
					(thickness 0.15)
				)
				(justify right)
			)
		)
		(property "License" "Apache-2.0"
			(at 370.84 179.07 0)
			(effects
				(font
					(size 1.27 1.27)
					(thickness 0.15)
				)
				(justify left bottom)
				(hide yes)
			)
		)
		(property "Author" "Antmicro"
			(at 373.38 179.07 0)
			(effects
				(font
					(size 1.27 1.27)
					(thickness 0.15)
				)
				(justify left bottom)
				(hide yes)
			)
		)
		(property "Tolerance" "1%"
			(at 355.6 179.07 0)
			(effects
				(font
					(size 1.27 1.27)
				)
				(justify left bottom)
				(hide yes)
			)
		)
		(pin "1"
		)
		(pin "2"
		)
		(instances
			(project "sdi-mipi-video-converter"
				(path ""
					(reference "R33")
					(unit 1)
				)
			)
		)
	)
	(symbol
		(lib_id "antmicroResistors0402:R_0R_0402")
		(at 311.15 201.93 0)
		(unit 1)
		(exclude_from_sim no)
		(in_bom yes)
		(on_board yes)
		(dnp no)
		(fields_autoplaced yes)
		(property "Reference" "R25"
			(at 313.69 205.74 0)
			(effects
				(font
					(size 1.27 1.27)
					(thickness 0.15)
				)
			)
		)
		(property "Value" "R_0R_0402"
			(at 331.47 214.63 0)
			(effects
				(font
					(size 1.27 1.27)
					(thickness 0.15)
				)
				(justify left bottom)
				(hide yes)
			)
		)
		(property "Footprint" "antmicro-footprints:R_0402_1005Metric"
			(at 331.47 217.17 0)
			(effects
				(font
					(size 1.27 1.27)
					(thickness 0.15)
				)
				(justify left bottom)
				(hide yes)
			)
		)
		(property "Datasheet" "https://industrial.panasonic.com/cdbs/www-data/pdf/RDA0000/AOA0000C301.pdf"
			(at 331.47 219.71 0)
			(effects
				(font
					(size 1.27 1.27)
					(thickness 0.15)
				)
				(justify left bottom)
				(hide yes)
			)
		)
		(property "Description" "SMD Chip Resistor, Jumper, 0 ohm, 100 mW, 0402 [1005 Metric], Thick Film, General Purpose"
			(at 311.15 201.93 0)
			(effects
				(font
					(size 1.27 1.27)
				)
				(hide yes)
			)
		)
		(property "Manufacturer" "Panasonic"
			(at 331.47 224.79 0)
			(effects
				(font
					(size 1.27 1.27)
					(thickness 0.15)
				)
				(justify left bottom)
				(hide yes)
			)
		)
		(property "MPN" "ERJ2GE0R00X"
			(at 331.47 222.25 0)
			(effects
				(font
					(size 1.27 1.27)
					(thickness 0.15)
				)
				(justify left bottom)
				(hide yes)
			)
		)
		(property "Val" "0R"
			(at 313.69 208.28 0)
			(effects
				(font
					(size 1.27 1.27)
					(thickness 0.15)
				)
			)
		)
		(property "License" "Apache-2.0"
			(at 331.47 227.33 0)
			(effects
				(font
					(size 1.27 1.27)
					(thickness 0.15)
				)
				(justify left bottom)
				(hide yes)
			)
		)
		(property "Author" "Antmicro"
			(at 331.47 229.87 0)
			(effects
				(font
					(size 1.27 1.27)
					(thickness 0.15)
				)
				(justify left bottom)
				(hide yes)
			)
		)
		(property "Tolerance" "~"
			(at 331.47 212.09 0)
			(effects
				(font
					(size 1.27 1.27)
				)
				(justify left bottom)
				(hide yes)
			)
		)
		(property "Current" "1A"
			(at 331.47 232.41 0)
			(effects
				(font
					(size 1.27 1.27)
					(thickness 0.15)
				)
				(justify left bottom)
				(hide yes)
			)
		)
		(pin "1"
		)
		(pin "2"
		)
		(instances
			(project "sdi-mipi-video-converter"
				(path ""
					(reference "R25")
					(unit 1)
				)
			)
		)
	)
	(symbol
		(lib_id "antmicropower:GND")
		(at 288.29 50.8 0)
		(unit 1)
		(exclude_from_sim no)
		(in_bom yes)
		(on_board yes)
		(dnp no)
		(fields_autoplaced yes)
		(property "Reference" "#PWR046"
			(at 297.18 53.34 0)
			(effects
				(font
					(size 1.27 1.27)
					(thickness 0.15)
				)
				(justify left bottom)
				(hide yes)
			)
		)
		(property "Value" "GND"
			(at 288.29 55.88 0)
			(effects
				(font
					(size 1.27 1.27)
					(thickness 0.15)
				)
			)
		)
		(property "Footprint" ""
			(at 297.18 58.42 0)
			(effects
				(font
					(size 1.27 1.27)
					(thickness 0.15)
				)
				(justify left bottom)
				(hide yes)
			)
		)
		(property "Datasheet" ""
			(at 297.18 63.5 0)
			(effects
				(font
					(size 1.27 1.27)
					(thickness 0.15)
				)
				(justify left bottom)
				(hide yes)
			)
		)
		(property "Description" ""
			(at 288.29 50.8 0)
			(effects
				(font
					(size 1.27 1.27)
				)
				(hide yes)
			)
		)
		(property "Author" "Antmicro"
			(at 297.18 58.42 0)
			(effects
				(font
					(size 1.27 1.27)
					(thickness 0.15)
				)
				(justify left bottom)
				(hide yes)
			)
		)
		(property "License" "Apache-2.0"
			(at 297.18 60.96 0)
			(effects
				(font
					(size 1.27 1.27)
					(thickness 0.15)
				)
				(justify left bottom)
				(hide yes)
			)
		)
		(pin "1"
		)
		(instances
			(project "sdi-mipi-video-converter"
				(path ""
					(reference "#PWR046")
					(unit 1)
				)
			)
		)
	)
	(symbol
		(lib_id "antmicroCapacitors0603:C_22u_0603")
		(at 377.19 85.09 90)
		(unit 1)
		(exclude_from_sim no)
		(in_bom yes)
		(on_board yes)
		(dnp no)
		(fields_autoplaced yes)
		(property "Reference" "C26"
			(at 379.73 81.2735 90)
			(effects
				(font
					(size 1.27 1.27)
					(thickness 0.15)
				)
				(justify right)
			)
		)
		(property "Value" "C_22u_0603"
			(at 387.35 64.77 0)
			(effects
				(font
					(size 1.27 1.27)
					(thickness 0.15)
				)
				(justify left bottom)
				(hide yes)
			)
		)
		(property "Footprint" "antmicro-footprints:C_0603_1608Metric"
			(at 389.89 64.77 0)
			(effects
				(font
					(size 1.27 1.27)
					(thickness 0.15)
				)
				(justify left bottom)
				(hide yes)
			)
		)
		(property "Datasheet" "https://www.murata.com/products/productdetail?partno=GRM188R60J226MEA0%23"
			(at 392.43 64.77 0)
			(effects
				(font
					(size 1.27 1.27)
					(thickness 0.15)
				)
				(justify left bottom)
				(hide yes)
			)
		)
		(property "Description" "SMD Multilayer Ceramic Capacitor, 22 µF, 6.3 V, 0603 [1608 Metric], ± 20%, X5R, GRM Series"
			(at 377.19 85.09 0)
			(effects
				(font
					(size 1.27 1.27)
				)
				(hide yes)
			)
		)
		(property "Manufacturer" "Murata"
			(at 397.51 64.77 0)
			(effects
				(font
					(size 1.27 1.27)
					(thickness 0.15)
				)
				(justify left bottom)
				(hide yes)
			)
		)
		(property "MPN" "GRM188R60J226MEA0D"
			(at 394.97 64.77 0)
			(effects
				(font
					(size 1.27 1.27)
					(thickness 0.15)
				)
				(justify left bottom)
				(hide yes)
			)
		)
		(property "Val" "22u"
			(at 379.73 83.8135 90)
			(effects
				(font
					(size 1.27 1.27)
					(thickness 0.15)
				)
				(justify right)
			)
		)
		(property "License" "Apache-2.0"
			(at 400.05 64.77 0)
			(effects
				(font
					(size 1.27 1.27)
					(thickness 0.15)
				)
				(justify left bottom)
				(hide yes)
			)
		)
		(property "Author" "Antmicro"
			(at 402.59 64.77 0)
			(effects
				(font
					(size 1.27 1.27)
					(thickness 0.15)
				)
				(justify left bottom)
				(hide yes)
			)
		)
		(property "Voltage" ""
			(at 405.13 64.77 0)
			(effects
				(font
					(size 1.27 1.27)
				)
				(justify left bottom)
				(hide yes)
			)
		)
		(property "Dielectric" ""
			(at 407.67 64.77 0)
			(effects
				(font
					(size 1.27 1.27)
				)
				(justify left bottom)
				(hide yes)
			)
		)
		(pin "1"
		)
		(pin "2"
		)
		(instances
			(project "sdi-mipi-video-converter"
				(path ""
					(reference "C26")
					(unit 1)
				)
			)
		)
	)
	(symbol
		(lib_id "antmicropower:GND")
		(at 29.21 205.74 0)
		(unit 1)
		(exclude_from_sim no)
		(in_bom yes)
		(on_board yes)
		(dnp no)
		(fields_autoplaced yes)
		(property "Reference" "#PWR02"
			(at 38.1 208.28 0)
			(effects
				(font
					(size 1.27 1.27)
					(thickness 0.15)
				)
				(justify left bottom)
				(hide yes)
			)
		)
		(property "Value" "GND"
			(at 29.21 210.82 0)
			(effects
				(font
					(size 1.27 1.27)
					(thickness 0.15)
				)
			)
		)
		(property "Footprint" ""
			(at 38.1 213.36 0)
			(effects
				(font
					(size 1.27 1.27)
					(thickness 0.15)
				)
				(justify left bottom)
				(hide yes)
			)
		)
		(property "Datasheet" ""
			(at 38.1 218.44 0)
			(effects
				(font
					(size 1.27 1.27)
					(thickness 0.15)
				)
				(justify left bottom)
				(hide yes)
			)
		)
		(property "Description" ""
			(at 29.21 205.74 0)
			(effects
				(font
					(size 1.27 1.27)
				)
				(hide yes)
			)
		)
		(property "Author" "Antmicro"
			(at 38.1 213.36 0)
			(effects
				(font
					(size 1.27 1.27)
					(thickness 0.15)
				)
				(justify left bottom)
				(hide yes)
			)
		)
		(property "License" "Apache-2.0"
			(at 38.1 215.9 0)
			(effects
				(font
					(size 1.27 1.27)
					(thickness 0.15)
				)
				(justify left bottom)
				(hide yes)
			)
		)
		(pin "1"
		)
		(instances
			(project "sdi-mipi-video-converter"
				(path ""
					(reference "#PWR02")
					(unit 1)
				)
			)
		)
	)
	(symbol
		(lib_id "antmicropower:GND")
		(at 269.24 116.84 0)
		(unit 1)
		(exclude_from_sim no)
		(in_bom yes)
		(on_board yes)
		(dnp no)
		(fields_autoplaced yes)
		(property "Reference" "#PWR037"
			(at 278.13 119.38 0)
			(effects
				(font
					(size 1.27 1.27)
					(thickness 0.15)
				)
				(justify left bottom)
				(hide yes)
			)
		)
		(property "Value" "GND"
			(at 269.24 121.92 0)
			(effects
				(font
					(size 1.27 1.27)
					(thickness 0.15)
				)
			)
		)
		(property "Footprint" ""
			(at 278.13 124.46 0)
			(effects
				(font
					(size 1.27 1.27)
					(thickness 0.15)
				)
				(justify left bottom)
				(hide yes)
			)
		)
		(property "Datasheet" ""
			(at 278.13 129.54 0)
			(effects
				(font
					(size 1.27 1.27)
					(thickness 0.15)
				)
				(justify left bottom)
				(hide yes)
			)
		)
		(property "Description" ""
			(at 269.24 116.84 0)
			(effects
				(font
					(size 1.27 1.27)
				)
				(hide yes)
			)
		)
		(property "Author" "Antmicro"
			(at 278.13 124.46 0)
			(effects
				(font
					(size 1.27 1.27)
					(thickness 0.15)
				)
				(justify left bottom)
				(hide yes)
			)
		)
		(property "License" "Apache-2.0"
			(at 278.13 127 0)
			(effects
				(font
					(size 1.27 1.27)
					(thickness 0.15)
				)
				(justify left bottom)
				(hide yes)
			)
		)
		(pin "1"
		)
		(instances
			(project "sdi-mipi-video-converter"
				(path ""
					(reference "#PWR037")
					(unit 1)
				)
			)
		)
	)
	(symbol
		(lib_id "antmicropower:GND")
		(at 377.19 91.44 0)
		(unit 1)
		(exclude_from_sim no)
		(in_bom yes)
		(on_board yes)
		(dnp no)
		(fields_autoplaced yes)
		(property "Reference" "#PWR068"
			(at 386.08 93.98 0)
			(effects
				(font
					(size 1.27 1.27)
					(thickness 0.15)
				)
				(justify left bottom)
				(hide yes)
			)
		)
		(property "Value" "GND"
			(at 374.65 92.7099 0)
			(effects
				(font
					(size 1.27 1.27)
					(thickness 0.15)
				)
				(justify right)
			)
		)
		(property "Footprint" ""
			(at 386.08 99.06 0)
			(effects
				(font
					(size 1.27 1.27)
					(thickness 0.15)
				)
				(justify left bottom)
				(hide yes)
			)
		)
		(property "Datasheet" ""
			(at 386.08 104.14 0)
			(effects
				(font
					(size 1.27 1.27)
					(thickness 0.15)
				)
				(justify left bottom)
				(hide yes)
			)
		)
		(property "Description" ""
			(at 377.19 91.44 0)
			(effects
				(font
					(size 1.27 1.27)
				)
				(hide yes)
			)
		)
		(property "Author" "Antmicro"
			(at 386.08 99.06 0)
			(effects
				(font
					(size 1.27 1.27)
					(thickness 0.15)
				)
				(justify left bottom)
				(hide yes)
			)
		)
		(property "License" "Apache-2.0"
			(at 386.08 101.6 0)
			(effects
				(font
					(size 1.27 1.27)
					(thickness 0.15)
				)
				(justify left bottom)
				(hide yes)
			)
		)
		(pin "1"
		)
		(instances
			(project "sdi-mipi-video-converter"
				(path ""
					(reference "#PWR068")
					(unit 1)
				)
			)
		)
	)
	(symbol
		(lib_id "antmicropower:GND")
		(at 123.19 87.63 0)
		(unit 1)
		(exclude_from_sim no)
		(in_bom yes)
		(on_board yes)
		(dnp no)
		(fields_autoplaced yes)
		(property "Reference" "#PWR025"
			(at 132.08 90.17 0)
			(effects
				(font
					(size 1.27 1.27)
					(thickness 0.15)
				)
				(justify left bottom)
				(hide yes)
			)
		)
		(property "Value" "GND"
			(at 123.19 92.71 0)
			(effects
				(font
					(size 1.27 1.27)
					(thickness 0.15)
				)
			)
		)
		(property "Footprint" ""
			(at 132.08 95.25 0)
			(effects
				(font
					(size 1.27 1.27)
					(thickness 0.15)
				)
				(justify left bottom)
				(hide yes)
			)
		)
		(property "Datasheet" ""
			(at 132.08 100.33 0)
			(effects
				(font
					(size 1.27 1.27)
					(thickness 0.15)
				)
				(justify left bottom)
				(hide yes)
			)
		)
		(property "Description" ""
			(at 123.19 87.63 0)
			(effects
				(font
					(size 1.27 1.27)
				)
				(hide yes)
			)
		)
		(property "Author" "Antmicro"
			(at 132.08 95.25 0)
			(effects
				(font
					(size 1.27 1.27)
					(thickness 0.15)
				)
				(justify left bottom)
				(hide yes)
			)
		)
		(property "License" "Apache-2.0"
			(at 132.08 97.79 0)
			(effects
				(font
					(size 1.27 1.27)
					(thickness 0.15)
				)
				(justify left bottom)
				(hide yes)
			)
		)
		(pin "1"
		)
		(instances
			(project "sdi-mipi-video-converter"
				(path ""
					(reference "#PWR025")
					(unit 1)
				)
			)
		)
	)
	(symbol
		(lib_id "antmicroFixedInductors:L_3u3_6.6A_XEL4030")
		(at 325.12 105.41 0)
		(unit 1)
		(exclude_from_sim no)
		(in_bom yes)
		(on_board yes)
		(dnp no)
		(fields_autoplaced yes)
		(property "Reference" "L2"
			(at 327.66 100.33 0)
			(effects
				(font
					(size 1.27 1.27)
					(thickness 0.15)
				)
			)
		)
		(property "Value" "L_3u3_5.9A_XEL4030"
			(at 339.09 107.95 0)
			(effects
				(font
					(size 1.27 1.27)
					(thickness 0.15)
				)
				(justify left bottom)
				(hide yes)
			)
		)
		(property "Footprint" "antmicro-footprints:L_Coilcraft-XEL4030"
			(at 339.09 113.03 0)
			(effects
				(font
					(size 1.27 1.27)
					(thickness 0.15)
				)
				(justify left bottom)
				(hide yes)
			)
		)
		(property "Datasheet" "https://www.coilcraft.com/getmedia/8245f050-f190-4295-8c41-7c03d662ee3d/xel4030.pdf"
			(at 339.09 115.57 0)
			(effects
				(font
					(size 1.27 1.27)
					(thickness 0.15)
				)
				(justify left bottom)
				(hide yes)
			)
		)
		(property "Description" "Power Inductor (SMT), AEC-Q200, 3.3 µH, 6.6 A, Shielded, 5.9 A, XEL4030"
			(at 325.12 105.41 0)
			(effects
				(font
					(size 1.27 1.27)
				)
				(hide yes)
			)
		)
		(property "MPN" "XEL4030-332MEC"
			(at 339.09 120.65 0)
			(effects
				(font
					(size 1.27 1.27)
					(thickness 0.15)
				)
				(justify left bottom)
				(hide yes)
			)
		)
		(property "Manufacturer" "Coilcraft"
			(at 339.09 118.11 0)
			(effects
				(font
					(size 1.27 1.27)
					(thickness 0.15)
				)
				(justify left bottom)
				(hide yes)
			)
		)
		(property "Val" "3u3/6.6A"
			(at 327.66 102.87 0)
			(effects
				(font
					(size 1.27 1.27)
					(thickness 0.15)
				)
			)
		)
		(property "Size" "4.0x4.0"
			(at 339.09 128.27 0)
			(effects
				(font
					(size 1.27 1.27)
					(thickness 0.15)
				)
				(justify left bottom)
				(hide yes)
			)
		)
		(property "ISat" "5.9 A"
			(at 339.09 121.92 0)
			(effects
				(font
					(size 1.27 1.27)
				)
				(justify left)
				(hide yes)
			)
		)
		(property "IMax" "6.6 A"
			(at 339.09 125.73 0)
			(effects
				(font
					(size 1.27 1.27)
					(thickness 0.15)
				)
				(justify left bottom)
				(hide yes)
			)
		)
		(property "Author" "Antmicro"
			(at 339.09 130.81 0)
			(effects
				(font
					(size 1.27 1.27)
					(thickness 0.15)
				)
				(justify left bottom)
				(hide yes)
			)
		)
		(property "License" "Apache-2.0"
			(at 339.09 133.35 0)
			(effects
				(font
					(size 1.27 1.27)
					(thickness 0.15)
				)
				(justify left bottom)
				(hide yes)
			)
		)
		(pin "1"
		)
		(pin "2"
		)
		(instances
			(project "sdi-mipi-video-converter"
				(path ""
					(reference "L2")
					(unit 1)
				)
			)
		)
	)
	(symbol
		(lib_id "antmicroResistors0402:R_3k01_0402")
		(at 336.55 80.01 90)
		(unit 1)
		(exclude_from_sim no)
		(in_bom yes)
		(on_board yes)
		(dnp no)
		(fields_autoplaced yes)
		(property "Reference" "R22"
			(at 339.09 76.1999 90)
			(effects
				(font
					(size 1.27 1.27)
					(thickness 0.15)
				)
				(justify right)
			)
		)
		(property "Value" "R_3k01_0402"
			(at 349.25 59.69 0)
			(effects
				(font
					(size 1.27 1.27)
					(thickness 0.15)
				)
				(justify left bottom)
				(hide yes)
			)
		)
		(property "Footprint" "antmicro-footprints:R_0402_1005Metric"
			(at 351.79 59.69 0)
			(effects
				(font
					(size 1.27 1.27)
					(thickness 0.15)
				)
				(justify left bottom)
				(hide yes)
			)
		)
		(property "Datasheet" "https://www.bourns.com/docs/product-datasheets/cr.pdf"
			(at 354.33 59.69 0)
			(effects
				(font
					(size 1.27 1.27)
					(thickness 0.15)
				)
				(justify left bottom)
				(hide yes)
			)
		)
		(property "Description" "SMD Chip Resistor, 3.01 kohm, ± 1%, 62.5 mW, 0402 [1005 Metric], Thick Film, General Purpose"
			(at 336.55 80.01 0)
			(effects
				(font
					(size 1.27 1.27)
				)
				(hide yes)
			)
		)
		(property "Manufacturer" "Bourns"
			(at 359.41 59.69 0)
			(effects
				(font
					(size 1.27 1.27)
					(thickness 0.15)
				)
				(justify left bottom)
				(hide yes)
			)
		)
		(property "MPN" "CR0402-FX-3011GLF"
			(at 356.87 59.69 0)
			(effects
				(font
					(size 1.27 1.27)
					(thickness 0.15)
				)
				(justify left bottom)
				(hide yes)
			)
		)
		(property "Val" "3k01"
			(at 339.09 78.7399 90)
			(effects
				(font
					(size 1.27 1.27)
					(thickness 0.15)
				)
				(justify right)
			)
		)
		(property "License" "Apache-2.0"
			(at 361.95 59.69 0)
			(effects
				(font
					(size 1.27 1.27)
					(thickness 0.15)
				)
				(justify left bottom)
				(hide yes)
			)
		)
		(property "Author" "Antmicro"
			(at 364.49 59.69 0)
			(effects
				(font
					(size 1.27 1.27)
					(thickness 0.15)
				)
				(justify left bottom)
				(hide yes)
			)
		)
		(property "Tolerance" "1%"
			(at 346.71 59.69 0)
			(effects
				(font
					(size 1.27 1.27)
				)
				(justify left bottom)
				(hide yes)
			)
		)
		(pin "1"
		)
		(pin "2"
		)
		(instances
			(project "sdi-mipi-video-converter"
				(path ""
					(reference "R22")
					(unit 1)
				)
			)
		)
	)
	(symbol
		(lib_id "antmicroLEDIndicationDiscrete:LED_G_0603_LTST-C190GKT")
		(at 241.3 259.08 270)
		(mirror x)
		(unit 1)
		(exclude_from_sim no)
		(in_bom yes)
		(on_board yes)
		(dnp no)
		(fields_autoplaced yes)
		(property "Reference" "D2"
			(at 245.11 255.27 90)
			(effects
				(font
					(size 1.27 1.27)
					(thickness 0.15)
				)
				(justify left)
			)
		)
		(property "Value" "LED_G_0603_LTST-C190GKT"
			(at 245.11 257.81 90)
			(effects
				(font
					(size 1.27 1.27)
					(thickness 0.15)
				)
				(justify left)
			)
		)
		(property "Footprint" "antmicro-footprints:LED_0603_1608Metric_G"
			(at 231.14 236.22 0)
			(effects
				(font
					(size 1.27 1.27)
					(thickness 0.15)
				)
				(justify left bottom)
				(hide yes)
			)
		)
		(property "Datasheet" "https://media.digikey.com/pdf/Data%20Sheets/Lite-On%20PDFs/LTST-C190GKT.pdf"
			(at 228.6 236.22 0)
			(effects
				(font
					(size 1.27 1.27)
					(thickness 0.15)
				)
				(justify left bottom)
				(hide yes)
			)
		)
		(property "Description" "LED, Green, SMD, 0603, 20 mA, 2.1 V, 569 nm"
			(at 241.3 259.08 0)
			(effects
				(font
					(size 1.27 1.27)
				)
				(hide yes)
			)
		)
		(property "MPN" "LTST-C190GKT"
			(at 226.06 236.22 0)
			(effects
				(font
					(size 1.27 1.27)
					(thickness 0.15)
				)
				(justify left bottom)
				(hide yes)
			)
		)
		(property "Manufacturer" "Lite-On"
			(at 223.52 236.22 0)
			(effects
				(font
					(size 1.27 1.27)
					(thickness 0.15)
				)
				(justify left bottom)
				(hide yes)
			)
		)
		(property "Author" "Antmicro"
			(at 220.98 236.22 0)
			(effects
				(font
					(size 1.27 1.27)
					(thickness 0.15)
				)
				(justify left bottom)
				(hide yes)
			)
		)
		(property "License" "Apache-2.0"
			(at 218.44 236.22 0)
			(effects
				(font
					(size 1.27 1.27)
					(thickness 0.15)
				)
				(justify left bottom)
				(hide yes)
			)
		)
		(property "Color" "Green"
			(at 245.11 259.0799 90)
			(effects
				(font
					(size 1.27 1.27)
				)
				(justify left)
				(hide yes)
			)
		)
		(pin "1"
		)
		(pin "2"
		)
		(instances
			(project "sdi-mipi-video-converter"
				(path ""
					(reference "D2")
					(unit 1)
				)
			)
		)
	)
	(symbol
		(lib_id "antmicropower:GND")
		(at 287.02 83.82 0)
		(unit 1)
		(exclude_from_sim no)
		(in_bom yes)
		(on_board yes)
		(dnp no)
		(fields_autoplaced yes)
		(property "Reference" "#PWR044"
			(at 295.91 86.36 0)
			(effects
				(font
					(size 1.27 1.27)
					(thickness 0.15)
				)
				(justify left bottom)
				(hide yes)
			)
		)
		(property "Value" "GND"
			(at 287.02 88.9 0)
			(effects
				(font
					(size 1.27 1.27)
					(thickness 0.15)
				)
			)
		)
		(property "Footprint" ""
			(at 295.91 91.44 0)
			(effects
				(font
					(size 1.27 1.27)
					(thickness 0.15)
				)
				(justify left bottom)
				(hide yes)
			)
		)
		(property "Datasheet" ""
			(at 295.91 96.52 0)
			(effects
				(font
					(size 1.27 1.27)
					(thickness 0.15)
				)
				(justify left bottom)
				(hide yes)
			)
		)
		(property "Description" ""
			(at 287.02 83.82 0)
			(effects
				(font
					(size 1.27 1.27)
				)
				(hide yes)
			)
		)
		(property "Author" "Antmicro"
			(at 295.91 91.44 0)
			(effects
				(font
					(size 1.27 1.27)
					(thickness 0.15)
				)
				(justify left bottom)
				(hide yes)
			)
		)
		(property "License" "Apache-2.0"
			(at 295.91 93.98 0)
			(effects
				(font
					(size 1.27 1.27)
					(thickness 0.15)
				)
				(justify left bottom)
				(hide yes)
			)
		)
		(pin "1"
		)
		(instances
			(project "sdi-mipi-video-converter"
				(path ""
					(reference "#PWR044")
					(unit 1)
				)
			)
		)
	)
	(symbol
		(lib_id "antmicroTestPoints:TP_0.75mm_SMD")
		(at 208.28 190.5 270)
		(unit 1)
		(exclude_from_sim no)
		(in_bom yes)
		(on_board yes)
		(dnp no)
		(fields_autoplaced yes)
		(property "Reference" "TP3"
			(at 210.82 193.675 90)
			(effects
				(font
					(size 1.27 1.27)
					(thickness 0.15)
				)
				(justify left)
			)
		)
		(property "Value" "TP_0.75mm_SMD"
			(at 200.66 208.28 0)
			(effects
				(font
					(size 1.27 1.27)
					(thickness 0.15)
				)
				(justify left bottom)
				(hide yes)
			)
		)
		(property "Footprint" "antmicro-footprints:TP_SMD_0.75mm"
			(at 198.12 208.28 0)
			(effects
				(font
					(size 1.27 1.27)
					(thickness 0.15)
				)
				(justify left bottom)
				(hide yes)
			)
		)
		(property "Datasheet" ""
			(at 195.58 208.28 0)
			(effects
				(font
					(size 1.27 1.27)
					(thickness 0.15)
				)
				(justify left bottom)
				(hide yes)
			)
		)
		(property "Description" "SMT test point"
			(at 208.28 190.5 0)
			(effects
				(font
					(size 1.27 1.27)
				)
				(hide yes)
			)
		)
		(property "MPN" ""
			(at 193.04 208.28 0)
			(effects
				(font
					(size 1.27 1.27)
					(thickness 0.15)
				)
				(justify left bottom)
				(hide yes)
			)
		)
		(property "Manufacturer" ""
			(at 190.5 208.28 0)
			(effects
				(font
					(size 1.27 1.27)
					(thickness 0.15)
				)
				(justify left bottom)
				(hide yes)
			)
		)
		(property "Author" "Antmicro"
			(at 187.96 208.28 0)
			(effects
				(font
					(size 1.27 1.27)
					(thickness 0.15)
				)
				(justify left bottom)
				(hide yes)
			)
		)
		(property "License" "Apache-2.0"
			(at 185.42 208.28 0)
			(effects
				(font
					(size 1.27 1.27)
					(thickness 0.15)
				)
				(justify left bottom)
				(hide yes)
			)
		)
		(pin "1"
		)
		(instances
			(project "sdi-mipi-video-converter"
				(path ""
					(reference "TP3")
					(unit 1)
				)
			)
		)
	)
	(symbol
		(lib_id "antmicropower:+5V")
		(at 260.35 38.1 0)
		(unit 1)
		(exclude_from_sim no)
		(in_bom yes)
		(on_board yes)
		(dnp no)
		(fields_autoplaced yes)
		(property "Reference" "#PWR034"
			(at 275.59 40.64 0)
			(effects
				(font
					(size 1.27 1.27)
					(thickness 0.15)
				)
				(justify left bottom)
				(hide yes)
			)
		)
		(property "Value" "+5V"
			(at 260.35 33.02 0)
			(effects
				(font
					(size 1.27 1.27)
					(thickness 0.15)
				)
			)
		)
		(property "Footprint" ""
			(at 275.59 45.72 0)
			(effects
				(font
					(size 1.27 1.27)
					(thickness 0.15)
				)
				(justify left bottom)
				(hide yes)
			)
		)
		(property "Datasheet" ""
			(at 275.59 48.26 0)
			(effects
				(font
					(size 1.27 1.27)
					(thickness 0.15)
				)
				(justify left bottom)
				(hide yes)
			)
		)
		(property "Description" ""
			(at 260.35 38.1 0)
			(effects
				(font
					(size 1.27 1.27)
				)
				(hide yes)
			)
		)
		(property "Author" "Antmicro"
			(at 275.59 45.72 0)
			(effects
				(font
					(size 1.27 1.27)
					(thickness 0.15)
				)
				(justify left bottom)
				(hide yes)
			)
		)
		(property "License" "Apache-2.0"
			(at 275.59 48.26 0)
			(effects
				(font
					(size 1.27 1.27)
					(thickness 0.15)
				)
				(justify left bottom)
				(hide yes)
			)
		)
		(pin "1"
		)
		(instances
			(project "sdi-mipi-video-converter"
				(path ""
					(reference "#PWR034")
					(unit 1)
				)
			)
		)
	)
	(symbol
		(lib_id "antmicroCapacitors0603:C_1u_0603")
		(at 297.18 238.76 90)
		(unit 1)
		(exclude_from_sim no)
		(in_bom yes)
		(on_board yes)
		(dnp no)
		(fields_autoplaced yes)
		(property "Reference" "C19"
			(at 299.72 234.9435 90)
			(effects
				(font
					(size 1.27 1.27)
					(thickness 0.15)
				)
				(justify right)
			)
		)
		(property "Value" "C_1u_0603"
			(at 307.34 218.44 0)
			(effects
				(font
					(size 1.27 1.27)
					(thickness 0.15)
				)
				(justify left bottom)
				(hide yes)
			)
		)
		(property "Footprint" "antmicro-footprints:C_0603_1608Metric"
			(at 309.88 218.44 0)
			(effects
				(font
					(size 1.27 1.27)
					(thickness 0.15)
				)
				(justify left bottom)
				(hide yes)
			)
		)
		(property "Datasheet" "https://spicat.kyocera-avx.com/product/mlcc/chartview/0603YD105KAT2A/"
			(at 312.42 218.44 0)
			(effects
				(font
					(size 1.27 1.27)
					(thickness 0.15)
				)
				(justify left bottom)
				(hide yes)
			)
		)
		(property "Description" "SMD Multilayer Ceramic Capacitor, 1 µF, 16 V, 0603 [1608 Metric], ± 10%, X5R, AVX 0603 MLCC"
			(at 297.18 238.76 0)
			(effects
				(font
					(size 1.27 1.27)
				)
				(hide yes)
			)
		)
		(property "Manufacturer" "KYOCERA AVX"
			(at 317.5 218.44 0)
			(effects
				(font
					(size 1.27 1.27)
					(thickness 0.15)
				)
				(justify left bottom)
				(hide yes)
			)
		)
		(property "MPN" "0603YD105KAT2A"
			(at 314.96 218.44 0)
			(effects
				(font
					(size 1.27 1.27)
					(thickness 0.15)
				)
				(justify left bottom)
				(hide yes)
			)
		)
		(property "Val" "1u"
			(at 299.72 237.4835 90)
			(effects
				(font
					(size 1.27 1.27)
					(thickness 0.15)
				)
				(justify right)
			)
		)
		(property "License" "Apache-2.0"
			(at 320.04 218.44 0)
			(effects
				(font
					(size 1.27 1.27)
					(thickness 0.15)
				)
				(justify left bottom)
				(hide yes)
			)
		)
		(property "Author" "Antmicro"
			(at 322.58 218.44 0)
			(effects
				(font
					(size 1.27 1.27)
					(thickness 0.15)
				)
				(justify left bottom)
				(hide yes)
			)
		)
		(property "Voltage" ""
			(at 325.12 218.44 0)
			(effects
				(font
					(size 1.27 1.27)
				)
				(justify left bottom)
				(hide yes)
			)
		)
		(property "Dielectric" ""
			(at 327.66 218.44 0)
			(effects
				(font
					(size 1.27 1.27)
				)
				(justify left bottom)
				(hide yes)
			)
		)
		(pin "1"
		)
		(pin "2"
		)
		(instances
			(project "sdi-mipi-video-converter"
				(path ""
					(reference "C19")
					(unit 1)
				)
			)
		)
	)
	(symbol
		(lib_id "antmicropower:+3.3V")
		(at 297.18 160.02 0)
		(unit 1)
		(exclude_from_sim no)
		(in_bom yes)
		(on_board yes)
		(dnp no)
		(fields_autoplaced yes)
		(property "Reference" "#PWR047"
			(at 297.18 163.83 0)
			(effects
				(font
					(size 1.27 1.27)
				)
				(hide yes)
			)
		)
		(property "Value" "+3V3"
			(at 297.18 154.94 0)
			(effects
				(font
					(size 1.27 1.27)
				)
			)
		)
		(property "Footprint" ""
			(at 297.18 160.02 0)
			(effects
				(font
					(size 1.27 1.27)
				)
				(hide yes)
			)
		)
		(property "Datasheet" ""
			(at 297.18 160.02 0)
			(effects
				(font
					(size 1.27 1.27)
				)
				(hide yes)
			)
		)
		(property "Description" ""
			(at 297.18 160.02 0)
			(effects
				(font
					(size 1.27 1.27)
				)
				(hide yes)
			)
		)
		(pin "1"
		)
		(instances
			(project "sdi-mipi-video-converter"
				(path ""
					(reference "#PWR047")
					(unit 1)
				)
			)
		)
	)
	(symbol
		(lib_id "antmicroPMICVoltageRegulatorsLinear:MP20073DH")
		(at 63.5 133.35 0)
		(unit 1)
		(exclude_from_sim no)
		(in_bom yes)
		(on_board yes)
		(dnp no)
		(fields_autoplaced yes)
		(property "Reference" "U1"
			(at 73.66 125.73 0)
			(effects
				(font
					(size 1.27 1.27)
					(thickness 0.15)
				)
			)
		)
		(property "Value" "MP20073DH"
			(at 73.66 128.27 0)
			(effects
				(font
					(size 1.27 1.27)
					(thickness 0.15)
				)
			)
		)
		(property "Footprint" "antmicro-footprints:MSOP-8-1EP_3x3x1.1mm_P0.65mm"
			(at 99.06 143.51 0)
			(effects
				(font
					(size 1.27 1.27)
					(thickness 0.15)
				)
				(justify left bottom)
				(hide yes)
			)
		)
		(property "Datasheet" "https://www.farnell.com/datasheets/2915039.pdf"
			(at 99.06 146.05 0)
			(effects
				(font
					(size 1.27 1.27)
					(thickness 0.15)
				)
				(justify left bottom)
				(hide yes)
			)
		)
		(property "Description" "DDR Termination Regulator, DDR2, DDR3, 1.3V to 6V in, 2A, MSOP-EP-8"
			(at 63.5 133.35 0)
			(effects
				(font
					(size 1.27 1.27)
				)
				(hide yes)
			)
		)
		(property "MPN" "MP20073DH-LF-P"
			(at 99.06 148.59 0)
			(effects
				(font
					(size 1.27 1.27)
					(thickness 0.15)
				)
				(justify left bottom)
				(hide yes)
			)
		)
		(property "Manufacturer" "Monolithic Power Systems"
			(at 99.06 151.13 0)
			(effects
				(font
					(size 1.27 1.27)
					(thickness 0.15)
				)
				(justify left bottom)
				(hide yes)
			)
		)
		(property "Author" "Antmicro"
			(at 99.06 153.67 0)
			(effects
				(font
					(size 1.27 1.27)
					(thickness 0.15)
				)
				(justify left bottom)
				(hide yes)
			)
		)
		(property "License" "Apache-2.0"
			(at 99.06 156.21 0)
			(effects
				(font
					(size 1.27 1.27)
					(thickness 0.15)
				)
				(justify left bottom)
				(hide yes)
			)
		)
		(pin "1"
		)
		(pin "2"
		)
		(pin "3"
		)
		(pin "4"
		)
		(pin "5"
		)
		(pin "6"
		)
		(pin "7"
		)
		(pin "8"
		)
		(pin "9"
		)
		(instances
			(project "sdi-mipi-video-converter"
				(path ""
					(reference "U1")
					(unit 1)
				)
			)
		)
	)
	(symbol
		(lib_id "antmicroTestPoints:TP_0.75mm_SMD")
		(at 214.63 190.5 270)
		(unit 1)
		(exclude_from_sim no)
		(in_bom yes)
		(on_board yes)
		(dnp no)
		(fields_autoplaced yes)
		(property "Reference" "TP4"
			(at 217.17 193.675 90)
			(effects
				(font
					(size 1.27 1.27)
					(thickness 0.15)
				)
				(justify left)
			)
		)
		(property "Value" "TP_0.75mm_SMD"
			(at 207.01 208.28 0)
			(effects
				(font
					(size 1.27 1.27)
					(thickness 0.15)
				)
				(justify left bottom)
				(hide yes)
			)
		)
		(property "Footprint" "antmicro-footprints:TP_SMD_0.75mm"
			(at 204.47 208.28 0)
			(effects
				(font
					(size 1.27 1.27)
					(thickness 0.15)
				)
				(justify left bottom)
				(hide yes)
			)
		)
		(property "Datasheet" ""
			(at 201.93 208.28 0)
			(effects
				(font
					(size 1.27 1.27)
					(thickness 0.15)
				)
				(justify left bottom)
				(hide yes)
			)
		)
		(property "Description" "SMT test point"
			(at 214.63 190.5 0)
			(effects
				(font
					(size 1.27 1.27)
				)
				(hide yes)
			)
		)
		(property "MPN" ""
			(at 199.39 208.28 0)
			(effects
				(font
					(size 1.27 1.27)
					(thickness 0.15)
				)
				(justify left bottom)
				(hide yes)
			)
		)
		(property "Manufacturer" ""
			(at 196.85 208.28 0)
			(effects
				(font
					(size 1.27 1.27)
					(thickness 0.15)
				)
				(justify left bottom)
				(hide yes)
			)
		)
		(property "Author" "Antmicro"
			(at 194.31 208.28 0)
			(effects
				(font
					(size 1.27 1.27)
					(thickness 0.15)
				)
				(justify left bottom)
				(hide yes)
			)
		)
		(property "License" "Apache-2.0"
			(at 191.77 208.28 0)
			(effects
				(font
					(size 1.27 1.27)
					(thickness 0.15)
				)
				(justify left bottom)
				(hide yes)
			)
		)
		(pin "1"
		)
		(instances
			(project "sdi-mipi-video-converter"
				(path ""
					(reference "TP4")
					(unit 1)
				)
			)
		)
	)
	(symbol
		(lib_id "antmicroTestPoints:TP_0.75mm_SMD")
		(at 201.93 190.5 270)
		(unit 1)
		(exclude_from_sim no)
		(in_bom yes)
		(on_board yes)
		(dnp no)
		(fields_autoplaced yes)
		(property "Reference" "TP2"
			(at 204.47 193.675 90)
			(effects
				(font
					(size 1.27 1.27)
					(thickness 0.15)
				)
				(justify left)
			)
		)
		(property "Value" "TP_0.75mm_SMD"
			(at 194.31 208.28 0)
			(effects
				(font
					(size 1.27 1.27)
					(thickness 0.15)
				)
				(justify left bottom)
				(hide yes)
			)
		)
		(property "Footprint" "antmicro-footprints:TP_SMD_0.75mm"
			(at 191.77 208.28 0)
			(effects
				(font
					(size 1.27 1.27)
					(thickness 0.15)
				)
				(justify left bottom)
				(hide yes)
			)
		)
		(property "Datasheet" ""
			(at 189.23 208.28 0)
			(effects
				(font
					(size 1.27 1.27)
					(thickness 0.15)
				)
				(justify left bottom)
				(hide yes)
			)
		)
		(property "Description" "SMT test point"
			(at 201.93 190.5 0)
			(effects
				(font
					(size 1.27 1.27)
				)
				(hide yes)
			)
		)
		(property "MPN" ""
			(at 186.69 208.28 0)
			(effects
				(font
					(size 1.27 1.27)
					(thickness 0.15)
				)
				(justify left bottom)
				(hide yes)
			)
		)
		(property "Manufacturer" ""
			(at 184.15 208.28 0)
			(effects
				(font
					(size 1.27 1.27)
					(thickness 0.15)
				)
				(justify left bottom)
				(hide yes)
			)
		)
		(property "Author" "Antmicro"
			(at 181.61 208.28 0)
			(effects
				(font
					(size 1.27 1.27)
					(thickness 0.15)
				)
				(justify left bottom)
				(hide yes)
			)
		)
		(property "License" "Apache-2.0"
			(at 179.07 208.28 0)
			(effects
				(font
					(size 1.27 1.27)
					(thickness 0.15)
				)
				(justify left bottom)
				(hide yes)
			)
		)
		(pin "1"
		)
		(instances
			(project "sdi-mipi-video-converter"
				(path ""
					(reference "TP2")
					(unit 1)
				)
			)
		)
	)
	(symbol
		(lib_id "antmicroCapacitors0402:C_100n_0402")
		(at 316.23 77.47 180)
		(unit 1)
		(exclude_from_sim no)
		(in_bom yes)
		(on_board yes)
		(dnp no)
		(fields_autoplaced yes)
		(property "Reference" "C9"
			(at 313.6836 82.55 0)
			(effects
				(font
					(size 1.27 1.27)
					(thickness 0.15)
				)
			)
		)
		(property "Value" "C_100n_0402"
			(at 295.91 67.31 0)
			(effects
				(font
					(size 1.27 1.27)
					(thickness 0.15)
				)
				(justify left bottom)
				(hide yes)
			)
		)
		(property "Footprint" "antmicro-footprints:C_0402_1005Metric"
			(at 295.91 64.77 0)
			(effects
				(font
					(size 1.27 1.27)
					(thickness 0.15)
				)
				(justify left bottom)
				(hide yes)
			)
		)
		(property "Datasheet" "https://www.murata.com/products/productdetail?partno=GRM155R61H104KE14%23"
			(at 295.91 62.23 0)
			(effects
				(font
					(size 1.27 1.27)
					(thickness 0.15)
				)
				(justify left bottom)
				(hide yes)
			)
		)
		(property "Description" "SMD Multilayer Ceramic Capacitor, 0.1 µF, 50 V, 0402 [1005 Metric], ± 10%, X5R, GRM Series"
			(at 316.23 77.47 0)
			(effects
				(font
					(size 1.27 1.27)
				)
				(hide yes)
			)
		)
		(property "Manufacturer" "Murata"
			(at 295.91 57.15 0)
			(effects
				(font
					(size 1.27 1.27)
					(thickness 0.15)
				)
				(justify left bottom)
				(hide yes)
			)
		)
		(property "MPN" "GRM155R61H104KE14D"
			(at 295.91 59.69 0)
			(effects
				(font
					(size 1.27 1.27)
					(thickness 0.15)
				)
				(justify left bottom)
				(hide yes)
			)
		)
		(property "Val" "100n"
			(at 313.6836 85.09 0)
			(effects
				(font
					(size 1.27 1.27)
					(thickness 0.15)
				)
			)
		)
		(property "License" "Apache-2.0"
			(at 295.91 54.61 0)
			(effects
				(font
					(size 1.27 1.27)
					(thickness 0.15)
				)
				(justify left bottom)
				(hide yes)
			)
		)
		(property "Author" "Antmicro"
			(at 295.91 52.07 0)
			(effects
				(font
					(size 1.27 1.27)
					(thickness 0.15)
				)
				(justify left bottom)
				(hide yes)
			)
		)
		(property "Voltage" "50V"
			(at 295.91 49.53 0)
			(effects
				(font
					(size 1.27 1.27)
				)
				(justify left bottom)
				(hide yes)
			)
		)
		(property "Dielectric" "X5R"
			(at 295.91 46.99 0)
			(effects
				(font
					(size 1.27 1.27)
				)
				(justify left bottom)
				(hide yes)
			)
		)
		(pin "1"
		)
		(pin "2"
		)
		(instances
			(project "sdi-mipi-video-converter"
				(path ""
					(reference "C9")
					(unit 1)
				)
			)
		)
	)
	(symbol
		(lib_id "antmicropower:+5V")
		(at 182.88 267.97 0)
		(unit 1)
		(exclude_from_sim no)
		(in_bom yes)
		(on_board yes)
		(dnp no)
		(fields_autoplaced yes)
		(property "Reference" "#PWR027"
			(at 198.12 270.51 0)
			(effects
				(font
					(size 1.27 1.27)
					(thickness 0.15)
				)
				(justify left bottom)
				(hide yes)
			)
		)
		(property "Value" "+5V"
			(at 182.88 262.89 0)
			(effects
				(font
					(size 1.27 1.27)
					(thickness 0.15)
				)
			)
		)
		(property "Footprint" ""
			(at 198.12 275.59 0)
			(effects
				(font
					(size 1.27 1.27)
					(thickness 0.15)
				)
				(justify left bottom)
				(hide yes)
			)
		)
		(property "Datasheet" ""
			(at 198.12 278.13 0)
			(effects
				(font
					(size 1.27 1.27)
					(thickness 0.15)
				)
				(justify left bottom)
				(hide yes)
			)
		)
		(property "Description" ""
			(at 182.88 267.97 0)
			(effects
				(font
					(size 1.27 1.27)
				)
				(hide yes)
			)
		)
		(property "Author" "Antmicro"
			(at 198.12 275.59 0)
			(effects
				(font
					(size 1.27 1.27)
					(thickness 0.15)
				)
				(justify left bottom)
				(hide yes)
			)
		)
		(property "License" "Apache-2.0"
			(at 198.12 278.13 0)
			(effects
				(font
					(size 1.27 1.27)
					(thickness 0.15)
				)
				(justify left bottom)
				(hide yes)
			)
		)
		(pin "1"
		)
		(instances
			(project "sdi-mipi-video-converter"
				(path ""
					(reference "#PWR027")
					(unit 1)
				)
			)
		)
	)
	(symbol
		(lib_id "antmicropower:+1V8")
		(at 227.33 187.96 0)
		(unit 1)
		(exclude_from_sim no)
		(in_bom yes)
		(on_board yes)
		(dnp no)
		(fields_autoplaced yes)
		(property "Reference" "#PWR035"
			(at 242.57 190.5 0)
			(effects
				(font
					(size 1.27 1.27)
					(thickness 0.15)
				)
				(justify left bottom)
				(hide yes)
			)
		)
		(property "Value" "+1V8"
			(at 227.33 182.88 0)
			(effects
				(font
					(size 1.27 1.27)
					(thickness 0.15)
				)
			)
		)
		(property "Footprint" ""
			(at 242.57 195.58 0)
			(effects
				(font
					(size 1.27 1.27)
					(thickness 0.15)
				)
				(justify left bottom)
				(hide yes)
			)
		)
		(property "Datasheet" ""
			(at 242.57 198.12 0)
			(effects
				(font
					(size 1.27 1.27)
					(thickness 0.15)
				)
				(justify left bottom)
				(hide yes)
			)
		)
		(property "Description" ""
			(at 227.33 187.96 0)
			(effects
				(font
					(size 1.27 1.27)
				)
				(hide yes)
			)
		)
		(property "Author" "Antmicro"
			(at 242.57 195.58 0)
			(effects
				(font
					(size 1.27 1.27)
					(thickness 0.15)
				)
				(justify left bottom)
				(hide yes)
			)
		)
		(property "License" "Apache-2.0"
			(at 242.57 198.12 0)
			(effects
				(font
					(size 1.27 1.27)
					(thickness 0.15)
				)
				(justify left bottom)
				(hide yes)
			)
		)
		(pin "1"
		)
		(instances
			(project "sdi-mipi-video-converter"
				(path ""
					(reference "#PWR035")
					(unit 1)
				)
			)
		)
	)
	(symbol
		(lib_id "antmicropower:+3.3V")
		(at 208.28 187.96 0)
		(unit 1)
		(exclude_from_sim no)
		(in_bom yes)
		(on_board yes)
		(dnp no)
		(fields_autoplaced yes)
		(property "Reference" "#PWR030"
			(at 208.28 191.77 0)
			(effects
				(font
					(size 1.27 1.27)
				)
				(hide yes)
			)
		)
		(property "Value" "+3V3"
			(at 208.28 182.88 0)
			(effects
				(font
					(size 1.27 1.27)
				)
			)
		)
		(property "Footprint" ""
			(at 208.28 187.96 0)
			(effects
				(font
					(size 1.27 1.27)
				)
				(hide yes)
			)
		)
		(property "Datasheet" ""
			(at 208.28 187.96 0)
			(effects
				(font
					(size 1.27 1.27)
				)
				(hide yes)
			)
		)
		(property "Description" ""
			(at 208.28 187.96 0)
			(effects
				(font
					(size 1.27 1.27)
				)
				(hide yes)
			)
		)
		(pin "1"
		)
		(instances
			(project "sdi-mipi-video-converter"
				(path ""
					(reference "#PWR030")
					(unit 1)
				)
			)
		)
	)
	(symbol
		(lib_id "antmicroResistorsmisc:R_0R_1206")
		(at 29.21 77.47 0)
		(unit 1)
		(exclude_from_sim no)
		(in_bom yes)
		(on_board yes)
		(dnp no)
		(fields_autoplaced yes)
		(property "Reference" "R4"
			(at 31.75 71.12 0)
			(effects
				(font
					(size 1.27 1.27)
					(thickness 0.15)
				)
			)
		)
		(property "Value" "R_0R_1206"
			(at 49.53 90.17 0)
			(effects
				(font
					(size 1.27 1.27)
					(thickness 0.15)
				)
				(justify left bottom)
				(hide yes)
			)
		)
		(property "Footprint" "antmicro-footprints:R_1206_3216Metric"
			(at 49.53 92.71 0)
			(effects
				(font
					(size 1.27 1.27)
					(thickness 0.15)
				)
				(justify left bottom)
				(hide yes)
			)
		)
		(property "Datasheet" "https://www.farnell.com/datasheets/2860635.pdf"
			(at 49.53 95.25 0)
			(effects
				(font
					(size 1.27 1.27)
					(thickness 0.15)
				)
				(justify left bottom)
				(hide yes)
			)
		)
		(property "Description" "Zero Ohm Resistor, Jumper, 1206 [3216 Metric], Thick Film, 250 mW, 2 A, Surface Mount Device"
			(at 29.21 77.47 0)
			(effects
				(font
					(size 1.27 1.27)
				)
				(hide yes)
			)
		)
		(property "Manufacturer" "Multicomp Pro"
			(at 49.53 100.33 0)
			(effects
				(font
					(size 1.27 1.27)
					(thickness 0.15)
				)
				(justify left bottom)
				(hide yes)
			)
		)
		(property "MPN" "MCMR12X000_PTL"
			(at 49.53 97.79 0)
			(effects
				(font
					(size 1.27 1.27)
					(thickness 0.15)
				)
				(justify left bottom)
				(hide yes)
			)
		)
		(property "Val" "0R"
			(at 31.75 73.66 0)
			(effects
				(font
					(size 1.27 1.27)
					(thickness 0.15)
				)
			)
		)
		(property "License" "Apache-2.0"
			(at 49.53 102.87 0)
			(effects
				(font
					(size 1.27 1.27)
					(thickness 0.15)
				)
				(justify left bottom)
				(hide yes)
			)
		)
		(property "Author" "Antmicro"
			(at 49.53 105.41 0)
			(effects
				(font
					(size 1.27 1.27)
					(thickness 0.15)
				)
				(justify left bottom)
				(hide yes)
			)
		)
		(property "Tolerance" "~"
			(at 49.53 87.63 0)
			(effects
				(font
					(size 1.27 1.27)
				)
				(justify left bottom)
				(hide yes)
			)
		)
		(property "Current" "2A"
			(at 49.53 107.95 0)
			(effects
				(font
					(size 1.27 1.27)
					(thickness 0.15)
				)
				(justify left bottom)
				(hide yes)
			)
		)
		(pin "1"
		)
		(pin "2"
		)
		(instances
			(project "sdi-mipi-video-converter"
				(path ""
					(reference "R4")
					(unit 1)
				)
			)
		)
	)
	(symbol
		(lib_id "antmicroCapacitors0603:C_22u_0603")
		(at 388.62 85.09 90)
		(unit 1)
		(exclude_from_sim no)
		(in_bom yes)
		(on_board yes)
		(dnp no)
		(fields_autoplaced yes)
		(property "Reference" "C32"
			(at 391.16 81.2735 90)
			(effects
				(font
					(size 1.27 1.27)
					(thickness 0.15)
				)
				(justify right)
			)
		)
		(property "Value" "C_22u_0603"
			(at 398.78 64.77 0)
			(effects
				(font
					(size 1.27 1.27)
					(thickness 0.15)
				)
				(justify left bottom)
				(hide yes)
			)
		)
		(property "Footprint" "antmicro-footprints:C_0603_1608Metric"
			(at 401.32 64.77 0)
			(effects
				(font
					(size 1.27 1.27)
					(thickness 0.15)
				)
				(justify left bottom)
				(hide yes)
			)
		)
		(property "Datasheet" "https://www.murata.com/products/productdetail?partno=GRM188R60J226MEA0%23"
			(at 403.86 64.77 0)
			(effects
				(font
					(size 1.27 1.27)
					(thickness 0.15)
				)
				(justify left bottom)
				(hide yes)
			)
		)
		(property "Description" "SMD Multilayer Ceramic Capacitor, 22 µF, 6.3 V, 0603 [1608 Metric], ± 20%, X5R, GRM Series"
			(at 388.62 85.09 0)
			(effects
				(font
					(size 1.27 1.27)
				)
				(hide yes)
			)
		)
		(property "Manufacturer" "Murata"
			(at 408.94 64.77 0)
			(effects
				(font
					(size 1.27 1.27)
					(thickness 0.15)
				)
				(justify left bottom)
				(hide yes)
			)
		)
		(property "MPN" "GRM188R60J226MEA0D"
			(at 406.4 64.77 0)
			(effects
				(font
					(size 1.27 1.27)
					(thickness 0.15)
				)
				(justify left bottom)
				(hide yes)
			)
		)
		(property "Val" "22u"
			(at 391.16 83.8135 90)
			(effects
				(font
					(size 1.27 1.27)
					(thickness 0.15)
				)
				(justify right)
			)
		)
		(property "License" "Apache-2.0"
			(at 411.48 64.77 0)
			(effects
				(font
					(size 1.27 1.27)
					(thickness 0.15)
				)
				(justify left bottom)
				(hide yes)
			)
		)
		(property "Author" "Antmicro"
			(at 414.02 64.77 0)
			(effects
				(font
					(size 1.27 1.27)
					(thickness 0.15)
				)
				(justify left bottom)
				(hide yes)
			)
		)
		(property "Voltage" ""
			(at 416.56 64.77 0)
			(effects
				(font
					(size 1.27 1.27)
				)
				(justify left bottom)
				(hide yes)
			)
		)
		(property "Dielectric" ""
			(at 419.1 64.77 0)
			(effects
				(font
					(size 1.27 1.27)
				)
				(justify left bottom)
				(hide yes)
			)
		)
		(pin "1"
		)
		(pin "2"
		)
		(instances
			(project "sdi-mipi-video-converter"
				(path ""
					(reference "C32")
					(unit 1)
				)
			)
		)
	)
	(symbol
		(lib_id "antmicroTestPoints:TP_0.75mm_SMD")
		(at 46.99 90.17 270)
		(unit 1)
		(exclude_from_sim no)
		(in_bom yes)
		(on_board yes)
		(dnp no)
		(fields_autoplaced yes)
		(property "Reference" "TP23"
			(at 49.53 93.3449 90)
			(effects
				(font
					(size 1.27 1.27)
					(thickness 0.15)
				)
				(justify left)
			)
		)
		(property "Value" "TP_0.75mm_SMD"
			(at 39.37 107.95 0)
			(effects
				(font
					(size 1.27 1.27)
					(thickness 0.15)
				)
				(justify left bottom)
				(hide yes)
			)
		)
		(property "Footprint" "antmicro-footprints:TP_SMD_0.75mm"
			(at 36.83 107.95 0)
			(effects
				(font
					(size 1.27 1.27)
					(thickness 0.15)
				)
				(justify left bottom)
				(hide yes)
			)
		)
		(property "Datasheet" ""
			(at 34.29 107.95 0)
			(effects
				(font
					(size 1.27 1.27)
					(thickness 0.15)
				)
				(justify left bottom)
				(hide yes)
			)
		)
		(property "Description" "SMT test point"
			(at 46.99 90.17 0)
			(effects
				(font
					(size 1.27 1.27)
				)
				(hide yes)
			)
		)
		(property "MPN" ""
			(at 31.75 107.95 0)
			(effects
				(font
					(size 1.27 1.27)
					(thickness 0.15)
				)
				(justify left bottom)
				(hide yes)
			)
		)
		(property "Manufacturer" ""
			(at 29.21 107.95 0)
			(effects
				(font
					(size 1.27 1.27)
					(thickness 0.15)
				)
				(justify left bottom)
				(hide yes)
			)
		)
		(property "Author" "Antmicro"
			(at 26.67 107.95 0)
			(effects
				(font
					(size 1.27 1.27)
					(thickness 0.15)
				)
				(justify left bottom)
				(hide yes)
			)
		)
		(property "License" "Apache-2.0"
			(at 24.13 107.95 0)
			(effects
				(font
					(size 1.27 1.27)
					(thickness 0.15)
				)
				(justify left bottom)
				(hide yes)
			)
		)
		(pin "1"
		)
		(instances
			(project "sdi-mipi-video-converter"
				(path ""
					(reference "TP23")
					(unit 1)
				)
			)
		)
	)
	(symbol
		(lib_id "antmicroTransistorsBipolarArrays:BCM857BS-7-F")
		(at 97.79 44.45 180)
		(unit 1)
		(exclude_from_sim no)
		(in_bom yes)
		(on_board yes)
		(dnp no)
		(fields_autoplaced yes)
		(property "Reference" "Q2"
			(at 73.66 38.9888 0)
			(effects
				(font
					(size 1.27 1.27)
					(thickness 0.15)
				)
			)
		)
		(property "Value" "BCM857BS-7-F"
			(at 73.66 41.5288 0)
			(effects
				(font
					(size 1.27 1.27)
					(thickness 0.15)
				)
			)
		)
		(property "Footprint" "antmicro-footprints:SOT-363"
			(at 74.93 39.37 0)
			(effects
				(font
					(size 1.27 1.27)
					(thickness 0.15)
				)
				(justify left bottom)
				(hide yes)
			)
		)
		(property "Datasheet" "https://www.diodes.com/assets/Datasheets/BCM857BS.pdf"
			(at 74.93 36.83 0)
			(effects
				(font
					(size 1.27 1.27)
					(thickness 0.15)
				)
				(justify left bottom)
				(hide yes)
			)
		)
		(property "Description" "Bipolar (BJT) Transistor Array, 2 Transistors, PNP, 45V, 100mA, SOT-363, Surface Mount"
			(at 97.79 44.45 0)
			(effects
				(font
					(size 1.27 1.27)
				)
				(hide yes)
			)
		)
		(property "MPN" "BCM857BS-7-F"
			(at 74.93 34.29 0)
			(effects
				(font
					(size 1.27 1.27)
					(thickness 0.15)
				)
				(justify left bottom)
				(hide yes)
			)
		)
		(property "Manufacturer" "Diodes Incorporated"
			(at 74.93 31.75 0)
			(effects
				(font
					(size 1.27 1.27)
					(thickness 0.15)
				)
				(justify left bottom)
				(hide yes)
			)
		)
		(property "Author" "Antmicro"
			(at 74.93 29.21 0)
			(effects
				(font
					(size 1.27 1.27)
					(thickness 0.15)
				)
				(justify left bottom)
				(hide yes)
			)
		)
		(property "License" "Apache-2.0"
			(at 74.93 26.67 0)
			(effects
				(font
					(size 1.27 1.27)
					(thickness 0.15)
				)
				(justify left bottom)
				(hide yes)
			)
		)
		(pin "1"
		)
		(pin "2"
		)
		(pin "3"
		)
		(pin "4"
		)
		(pin "5"
		)
		(pin "6"
		)
		(instances
			(project "sdi-mipi-video-converter"
				(path ""
					(reference "Q2")
					(unit 1)
				)
			)
		)
	)
	(symbol
		(lib_id "antmicroCapacitors0603:C_22u_0603")
		(at 377.19 118.11 90)
		(unit 1)
		(exclude_from_sim no)
		(in_bom yes)
		(on_board yes)
		(dnp no)
		(fields_autoplaced yes)
		(property "Reference" "C27"
			(at 379.73 114.2935 90)
			(effects
				(font
					(size 1.27 1.27)
					(thickness 0.15)
				)
				(justify right)
			)
		)
		(property "Value" "C_22u_0603"
			(at 387.35 97.79 0)
			(effects
				(font
					(size 1.27 1.27)
					(thickness 0.15)
				)
				(justify left bottom)
				(hide yes)
			)
		)
		(property "Footprint" "antmicro-footprints:C_0603_1608Metric"
			(at 389.89 97.79 0)
			(effects
				(font
					(size 1.27 1.27)
					(thickness 0.15)
				)
				(justify left bottom)
				(hide yes)
			)
		)
		(property "Datasheet" "https://www.murata.com/products/productdetail?partno=GRM188R60J226MEA0%23"
			(at 392.43 97.79 0)
			(effects
				(font
					(size 1.27 1.27)
					(thickness 0.15)
				)
				(justify left bottom)
				(hide yes)
			)
		)
		(property "Description" "SMD Multilayer Ceramic Capacitor, 22 µF, 6.3 V, 0603 [1608 Metric], ± 20%, X5R, GRM Series"
			(at 377.19 118.11 0)
			(effects
				(font
					(size 1.27 1.27)
				)
				(hide yes)
			)
		)
		(property "Manufacturer" "Murata"
			(at 397.51 97.79 0)
			(effects
				(font
					(size 1.27 1.27)
					(thickness 0.15)
				)
				(justify left bottom)
				(hide yes)
			)
		)
		(property "MPN" "GRM188R60J226MEA0D"
			(at 394.97 97.79 0)
			(effects
				(font
					(size 1.27 1.27)
					(thickness 0.15)
				)
				(justify left bottom)
				(hide yes)
			)
		)
		(property "Val" "22u"
			(at 379.73 116.8335 90)
			(effects
				(font
					(size 1.27 1.27)
					(thickness 0.15)
				)
				(justify right)
			)
		)
		(property "License" "Apache-2.0"
			(at 400.05 97.79 0)
			(effects
				(font
					(size 1.27 1.27)
					(thickness 0.15)
				)
				(justify left bottom)
				(hide yes)
			)
		)
		(property "Author" "Antmicro"
			(at 402.59 97.79 0)
			(effects
				(font
					(size 1.27 1.27)
					(thickness 0.15)
				)
				(justify left bottom)
				(hide yes)
			)
		)
		(property "Voltage" ""
			(at 405.13 97.79 0)
			(effects
				(font
					(size 1.27 1.27)
				)
				(justify left bottom)
				(hide yes)
			)
		)
		(property "Dielectric" ""
			(at 407.67 97.79 0)
			(effects
				(font
					(size 1.27 1.27)
				)
				(justify left bottom)
				(hide yes)
			)
		)
		(pin "1"
		)
		(pin "2"
		)
		(instances
			(project "sdi-mipi-video-converter"
				(path ""
					(reference "C27")
					(unit 1)
				)
			)
		)
	)
	(symbol
		(lib_id "antmicropower:GND")
		(at 355.6 91.44 0)
		(unit 1)
		(exclude_from_sim no)
		(in_bom yes)
		(on_board yes)
		(dnp no)
		(fields_autoplaced yes)
		(property "Reference" "#PWR059"
			(at 364.49 93.98 0)
			(effects
				(font
					(size 1.27 1.27)
					(thickness 0.15)
				)
				(justify left bottom)
				(hide yes)
			)
		)
		(property "Value" "GND"
			(at 355.6 96.52 0)
			(effects
				(font
					(size 1.27 1.27)
					(thickness 0.15)
				)
			)
		)
		(property "Footprint" ""
			(at 364.49 99.06 0)
			(effects
				(font
					(size 1.27 1.27)
					(thickness 0.15)
				)
				(justify left bottom)
				(hide yes)
			)
		)
		(property "Datasheet" ""
			(at 364.49 104.14 0)
			(effects
				(font
					(size 1.27 1.27)
					(thickness 0.15)
				)
				(justify left bottom)
				(hide yes)
			)
		)
		(property "Description" ""
			(at 355.6 91.44 0)
			(effects
				(font
					(size 1.27 1.27)
				)
				(hide yes)
			)
		)
		(property "Author" "Antmicro"
			(at 364.49 99.06 0)
			(effects
				(font
					(size 1.27 1.27)
					(thickness 0.15)
				)
				(justify left bottom)
				(hide yes)
			)
		)
		(property "License" "Apache-2.0"
			(at 364.49 101.6 0)
			(effects
				(font
					(size 1.27 1.27)
					(thickness 0.15)
				)
				(justify left bottom)
				(hide yes)
			)
		)
		(pin "1"
		)
		(instances
			(project "sdi-mipi-video-converter"
				(path ""
					(reference "#PWR059")
					(unit 1)
				)
			)
		)
	)
	(symbol
		(lib_id "antmicroResistors0402:R_22R_0402")
		(at 36.83 135.89 0)
		(mirror y)
		(unit 1)
		(exclude_from_sim no)
		(in_bom yes)
		(on_board yes)
		(dnp no)
		(property "Reference" "R7"
			(at 34.29 138.43 0)
			(effects
				(font
					(size 1.27 1.27)
					(thickness 0.15)
				)
			)
		)
		(property "Value" "R_22R_0402"
			(at 16.51 148.59 0)
			(effects
				(font
					(size 1.27 1.27)
					(thickness 0.15)
				)
				(justify left bottom)
				(hide yes)
			)
		)
		(property "Footprint" "antmicro-footprints:R_0402_1005Metric"
			(at 16.51 151.13 0)
			(effects
				(font
					(size 1.27 1.27)
					(thickness 0.15)
				)
				(justify left bottom)
				(hide yes)
			)
		)
		(property "Datasheet" "https://www.bourns.com/docs/product-datasheets/cr.pdf"
			(at 16.51 153.67 0)
			(effects
				(font
					(size 1.27 1.27)
					(thickness 0.15)
				)
				(justify left bottom)
				(hide yes)
			)
		)
		(property "Description" "SMD Chip Resistor, 22 ohm, ± 1%, 62.5 mW, 0402 [1005 Metric], Thick Film, General Purpose"
			(at 36.83 135.89 0)
			(effects
				(font
					(size 1.27 1.27)
				)
				(hide yes)
			)
		)
		(property "Manufacturer" "Bourns"
			(at 16.51 158.75 0)
			(effects
				(font
					(size 1.27 1.27)
					(thickness 0.15)
				)
				(justify left bottom)
				(hide yes)
			)
		)
		(property "MPN" "CR0402-FX-22R0GLF"
			(at 16.51 156.21 0)
			(effects
				(font
					(size 1.27 1.27)
					(thickness 0.15)
				)
				(justify left bottom)
				(hide yes)
			)
		)
		(property "Val" "22R"
			(at 34.29 140.335 0)
			(effects
				(font
					(size 1.27 1.27)
					(thickness 0.15)
				)
			)
		)
		(property "License" "Apache-2.0"
			(at 16.51 161.29 0)
			(effects
				(font
					(size 1.27 1.27)
					(thickness 0.15)
				)
				(justify left bottom)
				(hide yes)
			)
		)
		(property "Author" "Antmicro"
			(at 16.51 163.83 0)
			(effects
				(font
					(size 1.27 1.27)
					(thickness 0.15)
				)
				(justify left bottom)
				(hide yes)
			)
		)
		(property "Tolerance" "1%"
			(at 16.51 146.05 0)
			(effects
				(font
					(size 1.27 1.27)
				)
				(justify left bottom)
				(hide yes)
			)
		)
		(pin "1"
		)
		(pin "2"
		)
		(instances
			(project "sdi-mipi-video-converter"
				(path ""
					(reference "R7")
					(unit 1)
				)
			)
		)
	)
	(symbol
		(lib_id "antmicropower:GND")
		(at 355.6 124.46 0)
		(unit 1)
		(exclude_from_sim no)
		(in_bom yes)
		(on_board yes)
		(dnp no)
		(fields_autoplaced yes)
		(property "Reference" "#PWR060"
			(at 364.49 127 0)
			(effects
				(font
					(size 1.27 1.27)
					(thickness 0.15)
				)
				(justify left bottom)
				(hide yes)
			)
		)
		(property "Value" "GND"
			(at 355.6 129.54 0)
			(effects
				(font
					(size 1.27 1.27)
					(thickness 0.15)
				)
			)
		)
		(property "Footprint" ""
			(at 364.49 132.08 0)
			(effects
				(font
					(size 1.27 1.27)
					(thickness 0.15)
				)
				(justify left bottom)
				(hide yes)
			)
		)
		(property "Datasheet" ""
			(at 364.49 137.16 0)
			(effects
				(font
					(size 1.27 1.27)
					(thickness 0.15)
				)
				(justify left bottom)
				(hide yes)
			)
		)
		(property "Description" ""
			(at 355.6 124.46 0)
			(effects
				(font
					(size 1.27 1.27)
				)
				(hide yes)
			)
		)
		(property "Author" "Antmicro"
			(at 364.49 132.08 0)
			(effects
				(font
					(size 1.27 1.27)
					(thickness 0.15)
				)
				(justify left bottom)
				(hide yes)
			)
		)
		(property "License" "Apache-2.0"
			(at 364.49 134.62 0)
			(effects
				(font
					(size 1.27 1.27)
					(thickness 0.15)
				)
				(justify left bottom)
				(hide yes)
			)
		)
		(pin "1"
		)
		(instances
			(project "sdi-mipi-video-converter"
				(path ""
					(reference "#PWR060")
					(unit 1)
				)
			)
		)
	)
	(symbol
		(lib_id "antmicropower:GND")
		(at 182.88 275.59 0)
		(unit 1)
		(exclude_from_sim no)
		(in_bom yes)
		(on_board yes)
		(dnp no)
		(fields_autoplaced yes)
		(property "Reference" "#PWR0215"
			(at 191.77 278.13 0)
			(effects
				(font
					(size 1.27 1.27)
					(thickness 0.15)
				)
				(justify left bottom)
				(hide yes)
			)
		)
		(property "Value" "GND"
			(at 182.88 280.67 0)
			(effects
				(font
					(size 1.27 1.27)
					(thickness 0.15)
				)
			)
		)
		(property "Footprint" ""
			(at 191.77 283.21 0)
			(effects
				(font
					(size 1.27 1.27)
					(thickness 0.15)
				)
				(justify left bottom)
				(hide yes)
			)
		)
		(property "Datasheet" ""
			(at 191.77 288.29 0)
			(effects
				(font
					(size 1.27 1.27)
					(thickness 0.15)
				)
				(justify left bottom)
				(hide yes)
			)
		)
		(property "Description" ""
			(at 182.88 275.59 0)
			(effects
				(font
					(size 1.27 1.27)
				)
				(hide yes)
			)
		)
		(property "Author" "Antmicro"
			(at 191.77 283.21 0)
			(effects
				(font
					(size 1.27 1.27)
					(thickness 0.15)
				)
				(justify left bottom)
				(hide yes)
			)
		)
		(property "License" "Apache-2.0"
			(at 191.77 285.75 0)
			(effects
				(font
					(size 1.27 1.27)
					(thickness 0.15)
				)
				(justify left bottom)
				(hide yes)
			)
		)
		(pin "1"
		)
		(instances
			(project "sdi-mipi-video-converter"
				(path ""
					(reference "#PWR0215")
					(unit 1)
				)
			)
		)
	)
	(symbol
		(lib_id "antmicropower:GND")
		(at 62.23 156.21 0)
		(unit 1)
		(exclude_from_sim no)
		(in_bom yes)
		(on_board yes)
		(dnp no)
		(fields_autoplaced yes)
		(property "Reference" "#PWR0226"
			(at 71.12 158.75 0)
			(effects
				(font
					(size 1.27 1.27)
					(thickness 0.15)
				)
				(justify left bottom)
				(hide yes)
			)
		)
		(property "Value" "GND"
			(at 62.23 161.29 0)
			(effects
				(font
					(size 1.27 1.27)
					(thickness 0.15)
				)
			)
		)
		(property "Footprint" ""
			(at 71.12 163.83 0)
			(effects
				(font
					(size 1.27 1.27)
					(thickness 0.15)
				)
				(justify left bottom)
				(hide yes)
			)
		)
		(property "Datasheet" ""
			(at 71.12 168.91 0)
			(effects
				(font
					(size 1.27 1.27)
					(thickness 0.15)
				)
				(justify left bottom)
				(hide yes)
			)
		)
		(property "Description" ""
			(at 62.23 156.21 0)
			(effects
				(font
					(size 1.27 1.27)
				)
				(hide yes)
			)
		)
		(property "Author" "Antmicro"
			(at 71.12 163.83 0)
			(effects
				(font
					(size 1.27 1.27)
					(thickness 0.15)
				)
				(justify left bottom)
				(hide yes)
			)
		)
		(property "License" "Apache-2.0"
			(at 71.12 166.37 0)
			(effects
				(font
					(size 1.27 1.27)
					(thickness 0.15)
				)
				(justify left bottom)
				(hide yes)
			)
		)
		(pin "1"
		)
		(instances
			(project "sdi-mipi-video-converter"
				(path ""
					(reference "#PWR0226")
					(unit 1)
				)
			)
		)
	)
	(symbol
		(lib_id "antmicropower:+5V")
		(at 29.21 184.15 0)
		(unit 1)
		(exclude_from_sim no)
		(in_bom yes)
		(on_board yes)
		(dnp no)
		(fields_autoplaced yes)
		(property "Reference" "#PWR01"
			(at 44.45 186.69 0)
			(effects
				(font
					(size 1.27 1.27)
					(thickness 0.15)
				)
				(justify left bottom)
				(hide yes)
			)
		)
		(property "Value" "+5V"
			(at 29.21 179.07 0)
			(effects
				(font
					(size 1.27 1.27)
					(thickness 0.15)
				)
			)
		)
		(property "Footprint" ""
			(at 44.45 191.77 0)
			(effects
				(font
					(size 1.27 1.27)
					(thickness 0.15)
				)
				(justify left bottom)
				(hide yes)
			)
		)
		(property "Datasheet" ""
			(at 44.45 194.31 0)
			(effects
				(font
					(size 1.27 1.27)
					(thickness 0.15)
				)
				(justify left bottom)
				(hide yes)
			)
		)
		(property "Description" ""
			(at 29.21 184.15 0)
			(effects
				(font
					(size 1.27 1.27)
				)
				(hide yes)
			)
		)
		(property "Author" "Antmicro"
			(at 44.45 191.77 0)
			(effects
				(font
					(size 1.27 1.27)
					(thickness 0.15)
				)
				(justify left bottom)
				(hide yes)
			)
		)
		(property "License" "Apache-2.0"
			(at 44.45 194.31 0)
			(effects
				(font
					(size 1.27 1.27)
					(thickness 0.15)
				)
				(justify left bottom)
				(hide yes)
			)
		)
		(pin "1"
		)
		(instances
			(project "sdi-mipi-video-converter"
				(path ""
					(reference "#PWR01")
					(unit 1)
				)
			)
		)
	)
	(symbol
		(lib_id "antmicroPMICVoltageRegulatorsLinear:AP7330-W5-7")
		(at 317.5 231.14 0)
		(unit 1)
		(exclude_from_sim no)
		(in_bom yes)
		(on_board yes)
		(dnp no)
		(fields_autoplaced yes)
		(property "Reference" "U10"
			(at 325.12 224.79 0)
			(effects
				(font
					(size 1.27 1.27)
					(thickness 0.15)
				)
			)
		)
		(property "Value" "AP7330-W5-7"
			(at 325.12 227.33 0)
			(effects
				(font
					(size 1.27 1.27)
					(thickness 0.15)
				)
			)
		)
		(property "Footprint" "antmicro-footprints:SOT-23-5"
			(at 347.98 241.3 0)
			(effects
				(font
					(size 1.27 1.27)
					(thickness 0.15)
				)
				(justify left bottom)
				(hide yes)
			)
		)
		(property "Datasheet" "https://www.diodes.com/assets/Datasheets/AP7330.pdf"
			(at 347.98 243.84 0)
			(effects
				(font
					(size 1.27 1.27)
					(thickness 0.15)
				)
				(justify left bottom)
				(hide yes)
			)
		)
		(property "Description" "Voltage regulator"
			(at 317.5 231.14 0)
			(effects
				(font
					(size 1.27 1.27)
				)
				(hide yes)
			)
		)
		(property "MPN" "AP7330-W5-7"
			(at 347.98 246.38 0)
			(effects
				(font
					(size 1.27 1.27)
					(thickness 0.15)
				)
				(justify left bottom)
				(hide yes)
			)
		)
		(property "Manufacturer" "Diodes Incorporated"
			(at 347.98 248.92 0)
			(effects
				(font
					(size 1.27 1.27)
					(thickness 0.15)
				)
				(justify left bottom)
				(hide yes)
			)
		)
		(property "Author" "Antmicro"
			(at 347.98 251.46 0)
			(effects
				(font
					(size 1.27 1.27)
					(thickness 0.15)
				)
				(justify left bottom)
				(hide yes)
			)
		)
		(property "License" "Apache-2.0"
			(at 347.98 254 0)
			(effects
				(font
					(size 1.27 1.27)
					(thickness 0.15)
				)
				(justify left bottom)
				(hide yes)
			)
		)
		(pin "1"
		)
		(pin "2"
		)
		(pin "3"
		)
		(pin "4"
		)
		(pin "5"
		)
		(instances
			(project "sdi-mipi-video-converter"
				(path ""
					(reference "U10")
					(unit 1)
				)
			)
		)
	)
	(symbol
		(lib_id "antmicroResistors0402:R_24k_0402")
		(at 345.44 209.55 90)
		(unit 1)
		(exclude_from_sim no)
		(in_bom yes)
		(on_board yes)
		(dnp no)
		(fields_autoplaced yes)
		(property "Reference" "R34"
			(at 347.98 205.7399 90)
			(effects
				(font
					(size 1.27 1.27)
					(thickness 0.15)
				)
				(justify right)
			)
		)
		(property "Value" "R_24k_0402"
			(at 358.14 189.23 0)
			(effects
				(font
					(size 1.27 1.27)
					(thickness 0.15)
				)
				(justify left bottom)
				(hide yes)
			)
		)
		(property "Footprint" "antmicro-footprints:R_0402_1005Metric"
			(at 360.68 189.23 0)
			(effects
				(font
					(size 1.27 1.27)
					(thickness 0.15)
				)
				(justify left bottom)
				(hide yes)
			)
		)
		(property "Datasheet" "https://www.bourns.com/docs/product-datasheets/cr.pdf"
			(at 363.22 189.23 0)
			(effects
				(font
					(size 1.27 1.27)
					(thickness 0.15)
				)
				(justify left bottom)
				(hide yes)
			)
		)
		(property "Description" "SMD Chip Resistor, 24 kohm, ± 1%, 100 mW, 0402 [1005 Metric], Thick Film, Precision"
			(at 345.44 209.55 0)
			(effects
				(font
					(size 1.27 1.27)
				)
				(hide yes)
			)
		)
		(property "Manufacturer" "Bourns"
			(at 368.3 189.23 0)
			(effects
				(font
					(size 1.27 1.27)
					(thickness 0.15)
				)
				(justify left bottom)
				(hide yes)
			)
		)
		(property "MPN" "CR0402-FX-2402GLF"
			(at 365.76 189.23 0)
			(effects
				(font
					(size 1.27 1.27)
					(thickness 0.15)
				)
				(justify left bottom)
				(hide yes)
			)
		)
		(property "Val" "24k"
			(at 347.98 208.2799 90)
			(effects
				(font
					(size 1.27 1.27)
					(thickness 0.15)
				)
				(justify right)
			)
		)
		(property "License" "Apache-2.0"
			(at 370.84 189.23 0)
			(effects
				(font
					(size 1.27 1.27)
					(thickness 0.15)
				)
				(justify left bottom)
				(hide yes)
			)
		)
		(property "Author" "Antmicro"
			(at 373.38 189.23 0)
			(effects
				(font
					(size 1.27 1.27)
					(thickness 0.15)
				)
				(justify left bottom)
				(hide yes)
			)
		)
		(property "Tolerance" "1%"
			(at 355.6 189.23 0)
			(effects
				(font
					(size 1.27 1.27)
				)
				(justify left bottom)
				(hide yes)
			)
		)
		(pin "1"
		)
		(pin "2"
		)
		(instances
			(project "sdi-mipi-video-converter"
				(path ""
					(reference "R34")
					(unit 1)
				)
			)
		)
	)
	(symbol
		(lib_id "antmicropower:GND")
		(at 388.62 124.46 0)
		(unit 1)
		(exclude_from_sim no)
		(in_bom yes)
		(on_board yes)
		(dnp no)
		(fields_autoplaced yes)
		(property "Reference" "#PWR077"
			(at 397.51 127 0)
			(effects
				(font
					(size 1.27 1.27)
					(thickness 0.15)
				)
				(justify left bottom)
				(hide yes)
			)
		)
		(property "Value" "GND"
			(at 386.08 125.7299 0)
			(effects
				(font
					(size 1.27 1.27)
					(thickness 0.15)
				)
				(justify right)
			)
		)
		(property "Footprint" ""
			(at 397.51 132.08 0)
			(effects
				(font
					(size 1.27 1.27)
					(thickness 0.15)
				)
				(justify left bottom)
				(hide yes)
			)
		)
		(property "Datasheet" ""
			(at 397.51 137.16 0)
			(effects
				(font
					(size 1.27 1.27)
					(thickness 0.15)
				)
				(justify left bottom)
				(hide yes)
			)
		)
		(property "Description" ""
			(at 388.62 124.46 0)
			(effects
				(font
					(size 1.27 1.27)
				)
				(hide yes)
			)
		)
		(property "Author" "Antmicro"
			(at 397.51 132.08 0)
			(effects
				(font
					(size 1.27 1.27)
					(thickness 0.15)
				)
				(justify left bottom)
				(hide yes)
			)
		)
		(property "License" "Apache-2.0"
			(at 397.51 134.62 0)
			(effects
				(font
					(size 1.27 1.27)
					(thickness 0.15)
				)
				(justify left bottom)
				(hide yes)
			)
		)
		(pin "1"
		)
		(instances
			(project "sdi-mipi-video-converter"
				(path ""
					(reference "#PWR077")
					(unit 1)
				)
			)
		)
	)
	(symbol
		(lib_id "antmicropower:GND")
		(at 359.41 245.11 0)
		(unit 1)
		(exclude_from_sim no)
		(in_bom yes)
		(on_board yes)
		(dnp no)
		(fields_autoplaced yes)
		(property "Reference" "#PWR075"
			(at 368.3 247.65 0)
			(effects
				(font
					(size 1.27 1.27)
					(thickness 0.15)
				)
				(justify left bottom)
				(hide yes)
			)
		)
		(property "Value" "GND"
			(at 356.87 246.3799 0)
			(effects
				(font
					(size 1.27 1.27)
					(thickness 0.15)
				)
				(justify right)
			)
		)
		(property "Footprint" ""
			(at 368.3 252.73 0)
			(effects
				(font
					(size 1.27 1.27)
					(thickness 0.15)
				)
				(justify left bottom)
				(hide yes)
			)
		)
		(property "Datasheet" ""
			(at 368.3 257.81 0)
			(effects
				(font
					(size 1.27 1.27)
					(thickness 0.15)
				)
				(justify left bottom)
				(hide yes)
			)
		)
		(property "Description" ""
			(at 359.41 245.11 0)
			(effects
				(font
					(size 1.27 1.27)
				)
				(hide yes)
			)
		)
		(property "Author" "Antmicro"
			(at 368.3 252.73 0)
			(effects
				(font
					(size 1.27 1.27)
					(thickness 0.15)
				)
				(justify left bottom)
				(hide yes)
			)
		)
		(property "License" "Apache-2.0"
			(at 368.3 255.27 0)
			(effects
				(font
					(size 1.27 1.27)
					(thickness 0.15)
				)
				(justify left bottom)
				(hide yes)
			)
		)
		(pin "1"
		)
		(instances
			(project "sdi-mipi-video-converter"
				(path ""
					(reference "#PWR075")
					(unit 1)
				)
			)
		)
	)
	(symbol
		(lib_id "antmicroResistors0603:R_0R_0603")
		(at 349.25 191.77 0)
		(unit 1)
		(exclude_from_sim no)
		(in_bom yes)
		(on_board yes)
		(dnp no)
		(fields_autoplaced yes)
		(property "Reference" "R30"
			(at 351.79 185.42 0)
			(effects
				(font
					(size 1.27 1.27)
					(thickness 0.15)
				)
			)
		)
		(property "Value" "R_0R_0603"
			(at 369.57 204.47 0)
			(effects
				(font
					(size 1.27 1.27)
					(thickness 0.15)
				)
				(justify left bottom)
				(hide yes)
			)
		)
		(property "Footprint" "antmicro-footprints:R_0603_1608Metric"
			(at 369.57 207.01 0)
			(effects
				(font
					(size 1.27 1.27)
					(thickness 0.15)
				)
				(justify left bottom)
				(hide yes)
			)
		)
		(property "Datasheet" "https://www.bourns.com/docs/product-datasheets/cr.pdf?sfvrsn=574d41f6_14"
			(at 369.57 209.55 0)
			(effects
				(font
					(size 1.27 1.27)
					(thickness 0.15)
				)
				(justify left bottom)
				(hide yes)
			)
		)
		(property "Description" "Zero Ohm Resistor, Jumper, 0603 [1608 Metric], Thick Film, 100 mW, 1 A, Surface Mount Device, CR"
			(at 349.25 191.77 0)
			(effects
				(font
					(size 1.27 1.27)
				)
				(hide yes)
			)
		)
		(property "Manufacturer" "Bourns"
			(at 369.57 214.63 0)
			(effects
				(font
					(size 1.27 1.27)
					(thickness 0.15)
				)
				(justify left bottom)
				(hide yes)
			)
		)
		(property "MPN" "CR0603-J/-000ELF"
			(at 369.57 212.09 0)
			(effects
				(font
					(size 1.27 1.27)
					(thickness 0.15)
				)
				(justify left bottom)
				(hide yes)
			)
		)
		(property "Val" "0R"
			(at 351.79 187.96 0)
			(effects
				(font
					(size 1.27 1.27)
					(thickness 0.15)
				)
			)
		)
		(property "License" "Apache-2.0"
			(at 369.57 217.17 0)
			(effects
				(font
					(size 1.27 1.27)
					(thickness 0.15)
				)
				(justify left bottom)
				(hide yes)
			)
		)
		(property "Author" "Antmicro"
			(at 369.57 219.71 0)
			(effects
				(font
					(size 1.27 1.27)
					(thickness 0.15)
				)
				(justify left bottom)
				(hide yes)
			)
		)
		(property "Tolerance" "~"
			(at 369.57 201.93 0)
			(effects
				(font
					(size 1.27 1.27)
				)
				(justify left bottom)
				(hide yes)
			)
		)
		(property "Current" "1A"
			(at 369.57 222.25 0)
			(effects
				(font
					(size 1.27 1.27)
					(thickness 0.15)
				)
				(justify left bottom)
				(hide yes)
			)
		)
		(pin "1"
		)
		(pin "2"
		)
		(instances
			(project "sdi-mipi-video-converter"
				(path ""
					(reference "R30")
					(unit 1)
				)
			)
		)
	)
	(symbol
		(lib_id "antmicropower:GND")
		(at 345.44 245.11 0)
		(unit 1)
		(exclude_from_sim no)
		(in_bom yes)
		(on_board yes)
		(dnp no)
		(fields_autoplaced yes)
		(property "Reference" "#PWR067"
			(at 354.33 247.65 0)
			(effects
				(font
					(size 1.27 1.27)
					(thickness 0.15)
				)
				(justify left bottom)
				(hide yes)
			)
		)
		(property "Value" "GND"
			(at 345.44 250.19 0)
			(effects
				(font
					(size 1.27 1.27)
					(thickness 0.15)
				)
			)
		)
		(property "Footprint" ""
			(at 354.33 252.73 0)
			(effects
				(font
					(size 1.27 1.27)
					(thickness 0.15)
				)
				(justify left bottom)
				(hide yes)
			)
		)
		(property "Datasheet" ""
			(at 354.33 257.81 0)
			(effects
				(font
					(size 1.27 1.27)
					(thickness 0.15)
				)
				(justify left bottom)
				(hide yes)
			)
		)
		(property "Description" ""
			(at 345.44 245.11 0)
			(effects
				(font
					(size 1.27 1.27)
				)
				(hide yes)
			)
		)
		(property "Author" "Antmicro"
			(at 354.33 252.73 0)
			(effects
				(font
					(size 1.27 1.27)
					(thickness 0.15)
				)
				(justify left bottom)
				(hide yes)
			)
		)
		(property "License" "Apache-2.0"
			(at 354.33 255.27 0)
			(effects
				(font
					(size 1.27 1.27)
					(thickness 0.15)
				)
				(justify left bottom)
				(hide yes)
			)
		)
		(pin "1"
		)
		(instances
			(project "sdi-mipi-video-converter"
				(path ""
					(reference "#PWR067")
					(unit 1)
				)
			)
		)
	)
	(symbol
		(lib_id "antmicropower:GND")
		(at 377.19 124.46 0)
		(unit 1)
		(exclude_from_sim no)
		(in_bom yes)
		(on_board yes)
		(dnp no)
		(fields_autoplaced yes)
		(property "Reference" "#PWR069"
			(at 386.08 127 0)
			(effects
				(font
					(size 1.27 1.27)
					(thickness 0.15)
				)
				(justify left bottom)
				(hide yes)
			)
		)
		(property "Value" "GND"
			(at 374.65 125.7299 0)
			(effects
				(font
					(size 1.27 1.27)
					(thickness 0.15)
				)
				(justify right)
			)
		)
		(property "Footprint" ""
			(at 386.08 132.08 0)
			(effects
				(font
					(size 1.27 1.27)
					(thickness 0.15)
				)
				(justify left bottom)
				(hide yes)
			)
		)
		(property "Datasheet" ""
			(at 386.08 137.16 0)
			(effects
				(font
					(size 1.27 1.27)
					(thickness 0.15)
				)
				(justify left bottom)
				(hide yes)
			)
		)
		(property "Description" ""
			(at 377.19 124.46 0)
			(effects
				(font
					(size 1.27 1.27)
				)
				(hide yes)
			)
		)
		(property "Author" "Antmicro"
			(at 386.08 132.08 0)
			(effects
				(font
					(size 1.27 1.27)
					(thickness 0.15)
				)
				(justify left bottom)
				(hide yes)
			)
		)
		(property "License" "Apache-2.0"
			(at 386.08 134.62 0)
			(effects
				(font
					(size 1.27 1.27)
					(thickness 0.15)
				)
				(justify left bottom)
				(hide yes)
			)
		)
		(pin "1"
		)
		(instances
			(project "sdi-mipi-video-converter"
				(path ""
					(reference "#PWR069")
					(unit 1)
				)
			)
		)
	)
	(symbol
		(lib_id "antmicropower:GND")
		(at 109.22 143.51 0)
		(unit 1)
		(exclude_from_sim no)
		(in_bom yes)
		(on_board yes)
		(dnp no)
		(fields_autoplaced yes)
		(property "Reference" "#PWR0222"
			(at 118.11 146.05 0)
			(effects
				(font
					(size 1.27 1.27)
					(thickness 0.15)
				)
				(justify left bottom)
				(hide yes)
			)
		)
		(property "Value" "GND"
			(at 106.68 144.7799 0)
			(effects
				(font
					(size 1.27 1.27)
					(thickness 0.15)
				)
				(justify right)
			)
		)
		(property "Footprint" ""
			(at 118.11 151.13 0)
			(effects
				(font
					(size 1.27 1.27)
					(thickness 0.15)
				)
				(justify left bottom)
				(hide yes)
			)
		)
		(property "Datasheet" ""
			(at 118.11 156.21 0)
			(effects
				(font
					(size 1.27 1.27)
					(thickness 0.15)
				)
				(justify left bottom)
				(hide yes)
			)
		)
		(property "Description" ""
			(at 109.22 143.51 0)
			(effects
				(font
					(size 1.27 1.27)
				)
				(hide yes)
			)
		)
		(property "Author" "Antmicro"
			(at 118.11 151.13 0)
			(effects
				(font
					(size 1.27 1.27)
					(thickness 0.15)
				)
				(justify left bottom)
				(hide yes)
			)
		)
		(property "License" "Apache-2.0"
			(at 118.11 153.67 0)
			(effects
				(font
					(size 1.27 1.27)
					(thickness 0.15)
				)
				(justify left bottom)
				(hide yes)
			)
		)
		(pin "1"
		)
		(instances
			(project "sdi-mipi-video-converter"
				(path ""
					(reference "#PWR0222")
					(unit 1)
				)
			)
		)
	)
	(symbol
		(lib_id "antmicroTestPoints:TP_0.75mm_SMD")
		(at 220.98 190.5 270)
		(unit 1)
		(exclude_from_sim no)
		(in_bom yes)
		(on_board yes)
		(dnp no)
		(fields_autoplaced yes)
		(property "Reference" "TP5"
			(at 223.52 193.675 90)
			(effects
				(font
					(size 1.27 1.27)
					(thickness 0.15)
				)
				(justify left)
			)
		)
		(property "Value" "TP_0.75mm_SMD"
			(at 213.36 208.28 0)
			(effects
				(font
					(size 1.27 1.27)
					(thickness 0.15)
				)
				(justify left bottom)
				(hide yes)
			)
		)
		(property "Footprint" "antmicro-footprints:TP_SMD_0.75mm"
			(at 210.82 208.28 0)
			(effects
				(font
					(size 1.27 1.27)
					(thickness 0.15)
				)
				(justify left bottom)
				(hide yes)
			)
		)
		(property "Datasheet" ""
			(at 208.28 208.28 0)
			(effects
				(font
					(size 1.27 1.27)
					(thickness 0.15)
				)
				(justify left bottom)
				(hide yes)
			)
		)
		(property "Description" "SMT test point"
			(at 220.98 190.5 0)
			(effects
				(font
					(size 1.27 1.27)
				)
				(hide yes)
			)
		)
		(property "MPN" ""
			(at 205.74 208.28 0)
			(effects
				(font
					(size 1.27 1.27)
					(thickness 0.15)
				)
				(justify left bottom)
				(hide yes)
			)
		)
		(property "Manufacturer" ""
			(at 203.2 208.28 0)
			(effects
				(font
					(size 1.27 1.27)
					(thickness 0.15)
				)
				(justify left bottom)
				(hide yes)
			)
		)
		(property "Author" "Antmicro"
			(at 200.66 208.28 0)
			(effects
				(font
					(size 1.27 1.27)
					(thickness 0.15)
				)
				(justify left bottom)
				(hide yes)
			)
		)
		(property "License" "Apache-2.0"
			(at 198.12 208.28 0)
			(effects
				(font
					(size 1.27 1.27)
					(thickness 0.15)
				)
				(justify left bottom)
				(hide yes)
			)
		)
		(pin "1"
		)
		(instances
			(project "sdi-mipi-video-converter"
				(path ""
					(reference "TP5")
					(unit 1)
				)
			)
		)
	)
	(symbol
		(lib_id "antmicropower:+5V")
		(at 259.08 104.14 0)
		(unit 1)
		(exclude_from_sim no)
		(in_bom yes)
		(on_board yes)
		(dnp no)
		(fields_autoplaced yes)
		(property "Reference" "#PWR032"
			(at 274.32 106.68 0)
			(effects
				(font
					(size 1.27 1.27)
					(thickness 0.15)
				)
				(justify left bottom)
				(hide yes)
			)
		)
		(property "Value" "+5V"
			(at 259.08 99.06 0)
			(effects
				(font
					(size 1.27 1.27)
					(thickness 0.15)
				)
			)
		)
		(property "Footprint" ""
			(at 274.32 111.76 0)
			(effects
				(font
					(size 1.27 1.27)
					(thickness 0.15)
				)
				(justify left bottom)
				(hide yes)
			)
		)
		(property "Datasheet" ""
			(at 274.32 114.3 0)
			(effects
				(font
					(size 1.27 1.27)
					(thickness 0.15)
				)
				(justify left bottom)
				(hide yes)
			)
		)
		(property "Description" ""
			(at 259.08 104.14 0)
			(effects
				(font
					(size 1.27 1.27)
				)
				(hide yes)
			)
		)
		(property "Author" "Antmicro"
			(at 274.32 111.76 0)
			(effects
				(font
					(size 1.27 1.27)
					(thickness 0.15)
				)
				(justify left bottom)
				(hide yes)
			)
		)
		(property "License" "Apache-2.0"
			(at 274.32 114.3 0)
			(effects
				(font
					(size 1.27 1.27)
					(thickness 0.15)
				)
				(justify left bottom)
				(hide yes)
			)
		)
		(pin "1"
		)
		(instances
			(project "sdi-mipi-video-converter"
				(path ""
					(reference "#PWR032")
					(unit 1)
				)
			)
		)
	)
	(symbol
		(lib_id "antmicropower:+3.3V")
		(at 297.18 195.58 0)
		(unit 1)
		(exclude_from_sim no)
		(in_bom yes)
		(on_board yes)
		(dnp no)
		(fields_autoplaced yes)
		(property "Reference" "#PWR049"
			(at 297.18 199.39 0)
			(effects
				(font
					(size 1.27 1.27)
				)
				(hide yes)
			)
		)
		(property "Value" "+3V3"
			(at 297.18 190.5 0)
			(effects
				(font
					(size 1.27 1.27)
				)
			)
		)
		(property "Footprint" ""
			(at 297.18 195.58 0)
			(effects
				(font
					(size 1.27 1.27)
				)
				(hide yes)
			)
		)
		(property "Datasheet" ""
			(at 297.18 195.58 0)
			(effects
				(font
					(size 1.27 1.27)
				)
				(hide yes)
			)
		)
		(property "Description" ""
			(at 297.18 195.58 0)
			(effects
				(font
					(size 1.27 1.27)
				)
				(hide yes)
			)
		)
		(pin "1"
		)
		(instances
			(project "sdi-mipi-video-converter"
				(path ""
					(reference "#PWR049")
					(unit 1)
				)
			)
		)
	)
	(symbol
		(lib_id "antmicropower:GND")
		(at 359.41 210.82 0)
		(unit 1)
		(exclude_from_sim no)
		(in_bom yes)
		(on_board yes)
		(dnp no)
		(fields_autoplaced yes)
		(property "Reference" "#PWR073"
			(at 368.3 213.36 0)
			(effects
				(font
					(size 1.27 1.27)
					(thickness 0.15)
				)
				(justify left bottom)
				(hide yes)
			)
		)
		(property "Value" "GND"
			(at 359.41 215.9 0)
			(effects
				(font
					(size 1.27 1.27)
					(thickness 0.15)
				)
			)
		)
		(property "Footprint" ""
			(at 368.3 218.44 0)
			(effects
				(font
					(size 1.27 1.27)
					(thickness 0.15)
				)
				(justify left bottom)
				(hide yes)
			)
		)
		(property "Datasheet" ""
			(at 368.3 223.52 0)
			(effects
				(font
					(size 1.27 1.27)
					(thickness 0.15)
				)
				(justify left bottom)
				(hide yes)
			)
		)
		(property "Description" ""
			(at 359.41 210.82 0)
			(effects
				(font
					(size 1.27 1.27)
				)
				(hide yes)
			)
		)
		(property "Author" "Antmicro"
			(at 368.3 218.44 0)
			(effects
				(font
					(size 1.27 1.27)
					(thickness 0.15)
				)
				(justify left bottom)
				(hide yes)
			)
		)
		(property "License" "Apache-2.0"
			(at 368.3 220.98 0)
			(effects
				(font
					(size 1.27 1.27)
					(thickness 0.15)
				)
				(justify left bottom)
				(hide yes)
			)
		)
		(pin "1"
		)
		(instances
			(project "sdi-mipi-video-converter"
				(path ""
					(reference "#PWR073")
					(unit 1)
				)
			)
		)
	)
	(symbol
		(lib_id "antmicroCapacitors0402:C_100n_0402")
		(at 317.5 44.45 180)
		(unit 1)
		(exclude_from_sim no)
		(in_bom yes)
		(on_board yes)
		(dnp no)
		(fields_autoplaced yes)
		(property "Reference" "C15"
			(at 314.9536 49.53 0)
			(effects
				(font
					(size 1.27 1.27)
					(thickness 0.15)
				)
			)
		)
		(property "Value" "C_100n_0402"
			(at 297.18 34.29 0)
			(effects
				(font
					(size 1.27 1.27)
					(thickness 0.15)
				)
				(justify left bottom)
				(hide yes)
			)
		)
		(property "Footprint" "antmicro-footprints:C_0402_1005Metric"
			(at 297.18 31.75 0)
			(effects
				(font
					(size 1.27 1.27)
					(thickness 0.15)
				)
				(justify left bottom)
				(hide yes)
			)
		)
		(property "Datasheet" "https://www.murata.com/products/productdetail?partno=GRM155R61H104KE14%23"
			(at 297.18 29.21 0)
			(effects
				(font
					(size 1.27 1.27)
					(thickness 0.15)
				)
				(justify left bottom)
				(hide yes)
			)
		)
		(property "Description" "SMD Multilayer Ceramic Capacitor, 0.1 µF, 50 V, 0402 [1005 Metric], ± 10%, X5R, GRM Series"
			(at 317.5 44.45 0)
			(effects
				(font
					(size 1.27 1.27)
				)
				(hide yes)
			)
		)
		(property "Manufacturer" "Murata"
			(at 297.18 24.13 0)
			(effects
				(font
					(size 1.27 1.27)
					(thickness 0.15)
				)
				(justify left bottom)
				(hide yes)
			)
		)
		(property "MPN" "GRM155R61H104KE14D"
			(at 297.18 26.67 0)
			(effects
				(font
					(size 1.27 1.27)
					(thickness 0.15)
				)
				(justify left bottom)
				(hide yes)
			)
		)
		(property "Val" "100n"
			(at 314.9536 52.07 0)
			(effects
				(font
					(size 1.27 1.27)
					(thickness 0.15)
				)
			)
		)
		(property "License" "Apache-2.0"
			(at 297.18 21.59 0)
			(effects
				(font
					(size 1.27 1.27)
					(thickness 0.15)
				)
				(justify left bottom)
				(hide yes)
			)
		)
		(property "Author" "Antmicro"
			(at 297.18 19.05 0)
			(effects
				(font
					(size 1.27 1.27)
					(thickness 0.15)
				)
				(justify left bottom)
				(hide yes)
			)
		)
		(property "Voltage" "50V"
			(at 297.18 16.51 0)
			(effects
				(font
					(size 1.27 1.27)
				)
				(justify left bottom)
				(hide yes)
			)
		)
		(property "Dielectric" "X5R"
			(at 297.18 13.97 0)
			(effects
				(font
					(size 1.27 1.27)
				)
				(justify left bottom)
				(hide yes)
			)
		)
		(pin "1"
		)
		(pin "2"
		)
		(instances
			(project "sdi-mipi-video-converter"
				(path ""
					(reference "C15")
					(unit 1)
				)
			)
		)
	)
	(symbol
		(lib_id "antmicropower:+5V")
		(at 259.08 71.12 0)
		(unit 1)
		(exclude_from_sim no)
		(in_bom yes)
		(on_board yes)
		(dnp no)
		(fields_autoplaced yes)
		(property "Reference" "#PWR031"
			(at 274.32 73.66 0)
			(effects
				(font
					(size 1.27 1.27)
					(thickness 0.15)
				)
				(justify left bottom)
				(hide yes)
			)
		)
		(property "Value" "+5V"
			(at 259.08 66.04 0)
			(effects
				(font
					(size 1.27 1.27)
					(thickness 0.15)
				)
			)
		)
		(property "Footprint" ""
			(at 274.32 78.74 0)
			(effects
				(font
					(size 1.27 1.27)
					(thickness 0.15)
				)
				(justify left bottom)
				(hide yes)
			)
		)
		(property "Datasheet" ""
			(at 274.32 81.28 0)
			(effects
				(font
					(size 1.27 1.27)
					(thickness 0.15)
				)
				(justify left bottom)
				(hide yes)
			)
		)
		(property "Description" ""
			(at 259.08 71.12 0)
			(effects
				(font
					(size 1.27 1.27)
				)
				(hide yes)
			)
		)
		(property "Author" "Antmicro"
			(at 274.32 78.74 0)
			(effects
				(font
					(size 1.27 1.27)
					(thickness 0.15)
				)
				(justify left bottom)
				(hide yes)
			)
		)
		(property "License" "Apache-2.0"
			(at 274.32 81.28 0)
			(effects
				(font
					(size 1.27 1.27)
					(thickness 0.15)
				)
				(justify left bottom)
				(hide yes)
			)
		)
		(pin "1"
		)
		(instances
			(project "sdi-mipi-video-converter"
				(path ""
					(reference "#PWR031")
					(unit 1)
				)
			)
		)
	)
	(symbol
		(lib_id "antmicroCapacitors0603:C_10u_0603")
		(at 359.41 238.76 90)
		(unit 1)
		(exclude_from_sim no)
		(in_bom yes)
		(on_board yes)
		(dnp no)
		(fields_autoplaced yes)
		(property "Reference" "C31"
			(at 361.95 234.9435 90)
			(effects
				(font
					(size 1.27 1.27)
					(thickness 0.15)
				)
				(justify right)
			)
		)
		(property "Value" "C_10u_0603"
			(at 369.57 218.44 0)
			(effects
				(font
					(size 1.27 1.27)
					(thickness 0.15)
				)
				(justify left bottom)
				(hide yes)
			)
		)
		(property "Footprint" "antmicro-footprints:C_0603_1608Metric"
			(at 372.11 218.44 0)
			(effects
				(font
					(size 1.27 1.27)
					(thickness 0.15)
				)
				(justify left bottom)
				(hide yes)
			)
		)
		(property "Datasheet" "https://www.murata.com/products/productdetail?partno=GRM188R61A106KE69%23"
			(at 374.65 218.44 0)
			(effects
				(font
					(size 1.27 1.27)
					(thickness 0.15)
				)
				(justify left bottom)
				(hide yes)
			)
		)
		(property "Description" "SMD Multilayer Ceramic Capacitor, 10 µF, 10 V, 0603 [1608 Metric], ± 10%, X5R, GRM Series"
			(at 359.41 238.76 0)
			(effects
				(font
					(size 1.27 1.27)
				)
				(hide yes)
			)
		)
		(property "Manufacturer" "Murata"
			(at 379.73 218.44 0)
			(effects
				(font
					(size 1.27 1.27)
					(thickness 0.15)
				)
				(justify left bottom)
				(hide yes)
			)
		)
		(property "MPN" "GRM188R61A106KE69D"
			(at 377.19 218.44 0)
			(effects
				(font
					(size 1.27 1.27)
					(thickness 0.15)
				)
				(justify left bottom)
				(hide yes)
			)
		)
		(property "Val" "10u"
			(at 361.95 237.4835 90)
			(effects
				(font
					(size 1.27 1.27)
					(thickness 0.15)
				)
				(justify right)
			)
		)
		(property "License" "Apache-2.0"
			(at 382.27 218.44 0)
			(effects
				(font
					(size 1.27 1.27)
					(thickness 0.15)
				)
				(justify left bottom)
				(hide yes)
			)
		)
		(property "Author" "Antmicro"
			(at 384.81 218.44 0)
			(effects
				(font
					(size 1.27 1.27)
					(thickness 0.15)
				)
				(justify left bottom)
				(hide yes)
			)
		)
		(property "Voltage" ""
			(at 387.35 218.44 0)
			(effects
				(font
					(size 1.27 1.27)
				)
				(justify left bottom)
				(hide yes)
			)
		)
		(property "Dielectric" "template_dielectric"
			(at 389.89 218.44 0)
			(effects
				(font
					(size 1.27 1.27)
				)
				(justify left bottom)
				(hide yes)
			)
		)
		(pin "1"
		)
		(pin "2"
		)
		(instances
			(project "sdi-mipi-video-converter"
				(path ""
					(reference "C31")
					(unit 1)
				)
			)
		)
	)
	(symbol
		(lib_id "antmicroTestPoints:TP_0.75mm_SMD")
		(at 284.48 77.47 180)
		(unit 1)
		(exclude_from_sim no)
		(in_bom yes)
		(on_board yes)
		(dnp no)
		(fields_autoplaced yes)
		(property "Reference" "TP10"
			(at 279.4 77.4699 0)
			(effects
				(font
					(size 1.27 1.27)
					(thickness 0.15)
				)
				(justify left)
			)
		)
		(property "Value" "TP_0.75mm_SMD"
			(at 266.7 69.85 0)
			(effects
				(font
					(size 1.27 1.27)
					(thickness 0.15)
				)
				(justify left bottom)
				(hide yes)
			)
		)
		(property "Footprint" "antmicro-footprints:TP_SMD_0.75mm"
			(at 266.7 67.31 0)
			(effects
				(font
					(size 1.27 1.27)
					(thickness 0.15)
				)
				(justify left bottom)
				(hide yes)
			)
		)
		(property "Datasheet" ""
			(at 266.7 64.77 0)
			(effects
				(font
					(size 1.27 1.27)
					(thickness 0.15)
				)
				(justify left bottom)
				(hide yes)
			)
		)
		(property "Description" "SMT test point"
			(at 284.48 77.47 0)
			(effects
				(font
					(size 1.27 1.27)
				)
				(hide yes)
			)
		)
		(property "MPN" ""
			(at 266.7 62.23 0)
			(effects
				(font
					(size 1.27 1.27)
					(thickness 0.15)
				)
				(justify left bottom)
				(hide yes)
			)
		)
		(property "Manufacturer" ""
			(at 266.7 59.69 0)
			(effects
				(font
					(size 1.27 1.27)
					(thickness 0.15)
				)
				(justify left bottom)
				(hide yes)
			)
		)
		(property "Author" "Antmicro"
			(at 266.7 57.15 0)
			(effects
				(font
					(size 1.27 1.27)
					(thickness 0.15)
				)
				(justify left bottom)
				(hide yes)
			)
		)
		(property "License" "Apache-2.0"
			(at 266.7 54.61 0)
			(effects
				(font
					(size 1.27 1.27)
					(thickness 0.15)
				)
				(justify left bottom)
				(hide yes)
			)
		)
		(pin "1"
		)
		(instances
			(project "sdi-mipi-video-converter"
				(path ""
					(reference "TP10")
					(unit 1)
				)
			)
		)
	)
	(symbol
		(lib_id "antmicroResistorsmisc:R_0R_0805")
		(at 393.7 39.37 0)
		(unit 1)
		(exclude_from_sim no)
		(in_bom yes)
		(on_board yes)
		(dnp no)
		(fields_autoplaced yes)
		(property "Reference" "R40"
			(at 396.24 33.02 0)
			(effects
				(font
					(size 1.27 1.27)
					(thickness 0.15)
				)
			)
		)
		(property "Value" "R_0R_0805"
			(at 414.02 52.07 0)
			(effects
				(font
					(size 1.27 1.27)
					(thickness 0.15)
				)
				(justify left bottom)
				(hide yes)
			)
		)
		(property "Footprint" "antmicro-footprints:R_0805_2012Metric"
			(at 414.02 54.61 0)
			(effects
				(font
					(size 1.27 1.27)
					(thickness 0.15)
				)
				(justify left bottom)
				(hide yes)
			)
		)
		(property "Datasheet" "https://www.vishay.com/docs/20035/dcrcwe3.pdf"
			(at 414.02 57.15 0)
			(effects
				(font
					(size 1.27 1.27)
					(thickness 0.15)
				)
				(justify left bottom)
				(hide yes)
			)
		)
		(property "Description" "Zero Ohm Resistor, Jumper, 0805 [2012 Metric], Thick Film, 125 mW, 2.5 A, Surface Mount Device"
			(at 393.7 39.37 0)
			(effects
				(font
					(size 1.27 1.27)
				)
				(hide yes)
			)
		)
		(property "Manufacturer" "Vishay"
			(at 414.02 62.23 0)
			(effects
				(font
					(size 1.27 1.27)
					(thickness 0.15)
				)
				(justify left bottom)
				(hide yes)
			)
		)
		(property "MPN" "CRCW08050000Z0EA"
			(at 414.02 59.69 0)
			(effects
				(font
					(size 1.27 1.27)
					(thickness 0.15)
				)
				(justify left bottom)
				(hide yes)
			)
		)
		(property "Val" "0R"
			(at 396.24 35.56 0)
			(effects
				(font
					(size 1.27 1.27)
					(thickness 0.15)
				)
			)
		)
		(property "License" "Apache-2.0"
			(at 414.02 64.77 0)
			(effects
				(font
					(size 1.27 1.27)
					(thickness 0.15)
				)
				(justify left bottom)
				(hide yes)
			)
		)
		(property "Author" "Antmicro"
			(at 414.02 67.31 0)
			(effects
				(font
					(size 1.27 1.27)
					(thickness 0.15)
				)
				(justify left bottom)
				(hide yes)
			)
		)
		(property "Tolerance" "~"
			(at 414.02 49.53 0)
			(effects
				(font
					(size 1.27 1.27)
				)
				(justify left bottom)
				(hide yes)
			)
		)
		(property "Current" "2.5A"
			(at 414.02 69.85 0)
			(effects
				(font
					(size 1.27 1.27)
					(thickness 0.15)
				)
				(justify left bottom)
				(hide yes)
			)
		)
		(pin "1"
		)
		(pin "2"
		)
		(instances
			(project "sdi-mipi-video-converter"
				(path ""
					(reference "R40")
					(unit 1)
				)
			)
		)
	)
	(symbol
		(lib_id "antmicroResistors0402:R_0R_0402")
		(at 311.15 166.37 0)
		(unit 1)
		(exclude_from_sim no)
		(in_bom yes)
		(on_board yes)
		(dnp no)
		(fields_autoplaced yes)
		(property "Reference" "R24"
			(at 313.69 170.18 0)
			(effects
				(font
					(size 1.27 1.27)
					(thickness 0.15)
				)
			)
		)
		(property "Value" "R_0R_0402"
			(at 331.47 179.07 0)
			(effects
				(font
					(size 1.27 1.27)
					(thickness 0.15)
				)
				(justify left bottom)
				(hide yes)
			)
		)
		(property "Footprint" "antmicro-footprints:R_0402_1005Metric"
			(at 331.47 181.61 0)
			(effects
				(font
					(size 1.27 1.27)
					(thickness 0.15)
				)
				(justify left bottom)
				(hide yes)
			)
		)
		(property "Datasheet" "https://industrial.panasonic.com/cdbs/www-data/pdf/RDA0000/AOA0000C301.pdf"
			(at 331.47 184.15 0)
			(effects
				(font
					(size 1.27 1.27)
					(thickness 0.15)
				)
				(justify left bottom)
				(hide yes)
			)
		)
		(property "Description" "SMD Chip Resistor, Jumper, 0 ohm, 100 mW, 0402 [1005 Metric], Thick Film, General Purpose"
			(at 311.15 166.37 0)
			(effects
				(font
					(size 1.27 1.27)
				)
				(hide yes)
			)
		)
		(property "Manufacturer" "Panasonic"
			(at 331.47 189.23 0)
			(effects
				(font
					(size 1.27 1.27)
					(thickness 0.15)
				)
				(justify left bottom)
				(hide yes)
			)
		)
		(property "MPN" "ERJ2GE0R00X"
			(at 331.47 186.69 0)
			(effects
				(font
					(size 1.27 1.27)
					(thickness 0.15)
				)
				(justify left bottom)
				(hide yes)
			)
		)
		(property "Val" "0R"
			(at 313.69 172.72 0)
			(effects
				(font
					(size 1.27 1.27)
					(thickness 0.15)
				)
			)
		)
		(property "License" "Apache-2.0"
			(at 331.47 191.77 0)
			(effects
				(font
					(size 1.27 1.27)
					(thickness 0.15)
				)
				(justify left bottom)
				(hide yes)
			)
		)
		(property "Author" "Antmicro"
			(at 331.47 194.31 0)
			(effects
				(font
					(size 1.27 1.27)
					(thickness 0.15)
				)
				(justify left bottom)
				(hide yes)
			)
		)
		(property "Tolerance" "~"
			(at 331.47 176.53 0)
			(effects
				(font
					(size 1.27 1.27)
				)
				(justify left bottom)
				(hide yes)
			)
		)
		(property "Current" "1A"
			(at 331.47 196.85 0)
			(effects
				(font
					(size 1.27 1.27)
					(thickness 0.15)
				)
				(justify left bottom)
				(hide yes)
			)
		)
		(pin "1"
		)
		(pin "2"
		)
		(instances
			(project "sdi-mipi-video-converter"
				(path ""
					(reference "R24")
					(unit 1)
				)
			)
		)
	)
	(symbol
		(lib_id "antmicropower:GND")
		(at 367.03 91.44 0)
		(unit 1)
		(exclude_from_sim no)
		(in_bom yes)
		(on_board yes)
		(dnp no)
		(fields_autoplaced yes)
		(property "Reference" "#PWR062"
			(at 375.92 93.98 0)
			(effects
				(font
					(size 1.27 1.27)
					(thickness 0.15)
				)
				(justify left bottom)
				(hide yes)
			)
		)
		(property "Value" "GND"
			(at 367.03 96.52 0)
			(effects
				(font
					(size 1.27 1.27)
					(thickness 0.15)
				)
			)
		)
		(property "Footprint" ""
			(at 375.92 99.06 0)
			(effects
				(font
					(size 1.27 1.27)
					(thickness 0.15)
				)
				(justify left bottom)
				(hide yes)
			)
		)
		(property "Datasheet" ""
			(at 375.92 104.14 0)
			(effects
				(font
					(size 1.27 1.27)
					(thickness 0.15)
				)
				(justify left bottom)
				(hide yes)
			)
		)
		(property "Description" ""
			(at 367.03 91.44 0)
			(effects
				(font
					(size 1.27 1.27)
				)
				(hide yes)
			)
		)
		(property "Author" "Antmicro"
			(at 375.92 99.06 0)
			(effects
				(font
					(size 1.27 1.27)
					(thickness 0.15)
				)
				(justify left bottom)
				(hide yes)
			)
		)
		(property "License" "Apache-2.0"
			(at 375.92 101.6 0)
			(effects
				(font
					(size 1.27 1.27)
					(thickness 0.15)
				)
				(justify left bottom)
				(hide yes)
			)
		)
		(pin "1"
		)
		(instances
			(project "sdi-mipi-video-converter"
				(path ""
					(reference "#PWR062")
					(unit 1)
				)
			)
		)
	)
	(symbol
		(lib_id "antmicropower:GND")
		(at 337.82 58.42 0)
		(unit 1)
		(exclude_from_sim no)
		(in_bom yes)
		(on_board yes)
		(dnp no)
		(fields_autoplaced yes)
		(property "Reference" "#PWR055"
			(at 346.71 60.96 0)
			(effects
				(font
					(size 1.27 1.27)
					(thickness 0.15)
				)
				(justify left bottom)
				(hide yes)
			)
		)
		(property "Value" "GND"
			(at 337.82 63.5 0)
			(effects
				(font
					(size 1.27 1.27)
					(thickness 0.15)
				)
			)
		)
		(property "Footprint" ""
			(at 346.71 66.04 0)
			(effects
				(font
					(size 1.27 1.27)
					(thickness 0.15)
				)
				(justify left bottom)
				(hide yes)
			)
		)
		(property "Datasheet" ""
			(at 346.71 71.12 0)
			(effects
				(font
					(size 1.27 1.27)
					(thickness 0.15)
				)
				(justify left bottom)
				(hide yes)
			)
		)
		(property "Description" ""
			(at 337.82 58.42 0)
			(effects
				(font
					(size 1.27 1.27)
				)
				(hide yes)
			)
		)
		(property "Author" "Antmicro"
			(at 346.71 66.04 0)
			(effects
				(font
					(size 1.27 1.27)
					(thickness 0.15)
				)
				(justify left bottom)
				(hide yes)
			)
		)
		(property "License" "Apache-2.0"
			(at 346.71 68.58 0)
			(effects
				(font
					(size 1.27 1.27)
					(thickness 0.15)
				)
				(justify left bottom)
				(hide yes)
			)
		)
		(pin "1"
		)
		(instances
			(project "sdi-mipi-video-converter"
				(path ""
					(reference "#PWR055")
					(unit 1)
				)
			)
		)
	)
	(symbol
		(lib_id "antmicropower:GND")
		(at 365.76 124.46 0)
		(unit 1)
		(exclude_from_sim no)
		(in_bom yes)
		(on_board yes)
		(dnp no)
		(fields_autoplaced yes)
		(property "Reference" "#PWR063"
			(at 374.65 127 0)
			(effects
				(font
					(size 1.27 1.27)
					(thickness 0.15)
				)
				(justify left bottom)
				(hide yes)
			)
		)
		(property "Value" "GND"
			(at 365.76 129.54 0)
			(effects
				(font
					(size 1.27 1.27)
					(thickness 0.15)
				)
			)
		)
		(property "Footprint" ""
			(at 374.65 132.08 0)
			(effects
				(font
					(size 1.27 1.27)
					(thickness 0.15)
				)
				(justify left bottom)
				(hide yes)
			)
		)
		(property "Datasheet" ""
			(at 374.65 137.16 0)
			(effects
				(font
					(size 1.27 1.27)
					(thickness 0.15)
				)
				(justify left bottom)
				(hide yes)
			)
		)
		(property "Description" ""
			(at 365.76 124.46 0)
			(effects
				(font
					(size 1.27 1.27)
				)
				(hide yes)
			)
		)
		(property "Author" "Antmicro"
			(at 374.65 132.08 0)
			(effects
				(font
					(size 1.27 1.27)
					(thickness 0.15)
				)
				(justify left bottom)
				(hide yes)
			)
		)
		(property "License" "Apache-2.0"
			(at 374.65 134.62 0)
			(effects
				(font
					(size 1.27 1.27)
					(thickness 0.15)
				)
				(justify left bottom)
				(hide yes)
			)
		)
		(pin "1"
		)
		(instances
			(project "sdi-mipi-video-converter"
				(path ""
					(reference "#PWR063")
					(unit 1)
				)
			)
		)
	)
	(symbol
		(lib_id "antmicropower:GND")
		(at 73.66 104.14 0)
		(unit 1)
		(exclude_from_sim no)
		(in_bom yes)
		(on_board yes)
		(dnp no)
		(fields_autoplaced yes)
		(property "Reference" "#PWR0245"
			(at 82.55 106.68 0)
			(effects
				(font
					(size 1.27 1.27)
					(thickness 0.15)
				)
				(justify left bottom)
				(hide yes)
			)
		)
		(property "Value" "GND"
			(at 73.66 109.22 0)
			(effects
				(font
					(size 1.27 1.27)
					(thickness 0.15)
				)
			)
		)
		(property "Footprint" ""
			(at 82.55 111.76 0)
			(effects
				(font
					(size 1.27 1.27)
					(thickness 0.15)
				)
				(justify left bottom)
				(hide yes)
			)
		)
		(property "Datasheet" ""
			(at 82.55 116.84 0)
			(effects
				(font
					(size 1.27 1.27)
					(thickness 0.15)
				)
				(justify left bottom)
				(hide yes)
			)
		)
		(property "Description" ""
			(at 73.66 104.14 0)
			(effects
				(font
					(size 1.27 1.27)
				)
				(hide yes)
			)
		)
		(property "Author" "Antmicro"
			(at 82.55 111.76 0)
			(effects
				(font
					(size 1.27 1.27)
					(thickness 0.15)
				)
				(justify left bottom)
				(hide yes)
			)
		)
		(property "License" "Apache-2.0"
			(at 82.55 114.3 0)
			(effects
				(font
					(size 1.27 1.27)
					(thickness 0.15)
				)
				(justify left bottom)
				(hide yes)
			)
		)
		(pin "1"
		)
		(instances
			(project "sdi-mipi-video-converter"
				(path ""
					(reference "#PWR0245")
					(unit 1)
				)
			)
		)
	)
	(symbol
		(lib_id "antmicroCapacitors0603:C_1u_0603")
		(at 297.18 204.47 90)
		(unit 1)
		(exclude_from_sim no)
		(in_bom yes)
		(on_board yes)
		(dnp no)
		(fields_autoplaced yes)
		(property "Reference" "C18"
			(at 299.72 200.6535 90)
			(effects
				(font
					(size 1.27 1.27)
					(thickness 0.15)
				)
				(justify right)
			)
		)
		(property "Value" "C_1u_0603"
			(at 307.34 184.15 0)
			(effects
				(font
					(size 1.27 1.27)
					(thickness 0.15)
				)
				(justify left bottom)
				(hide yes)
			)
		)
		(property "Footprint" "antmicro-footprints:C_0603_1608Metric"
			(at 309.88 184.15 0)
			(effects
				(font
					(size 1.27 1.27)
					(thickness 0.15)
				)
				(justify left bottom)
				(hide yes)
			)
		)
		(property "Datasheet" "https://spicat.kyocera-avx.com/product/mlcc/chartview/0603YD105KAT2A/"
			(at 312.42 184.15 0)
			(effects
				(font
					(size 1.27 1.27)
					(thickness 0.15)
				)
				(justify left bottom)
				(hide yes)
			)
		)
		(property "Description" "SMD Multilayer Ceramic Capacitor, 1 µF, 16 V, 0603 [1608 Metric], ± 10%, X5R, AVX 0603 MLCC"
			(at 297.18 204.47 0)
			(effects
				(font
					(size 1.27 1.27)
				)
				(hide yes)
			)
		)
		(property "Manufacturer" "KYOCERA AVX"
			(at 317.5 184.15 0)
			(effects
				(font
					(size 1.27 1.27)
					(thickness 0.15)
				)
				(justify left bottom)
				(hide yes)
			)
		)
		(property "MPN" "0603YD105KAT2A"
			(at 314.96 184.15 0)
			(effects
				(font
					(size 1.27 1.27)
					(thickness 0.15)
				)
				(justify left bottom)
				(hide yes)
			)
		)
		(property "Val" "1u"
			(at 299.72 203.1935 90)
			(effects
				(font
					(size 1.27 1.27)
					(thickness 0.15)
				)
				(justify right)
			)
		)
		(property "License" "Apache-2.0"
			(at 320.04 184.15 0)
			(effects
				(font
					(size 1.27 1.27)
					(thickness 0.15)
				)
				(justify left bottom)
				(hide yes)
			)
		)
		(property "Author" "Antmicro"
			(at 322.58 184.15 0)
			(effects
				(font
					(size 1.27 1.27)
					(thickness 0.15)
				)
				(justify left bottom)
				(hide yes)
			)
		)
		(property "Voltage" ""
			(at 325.12 184.15 0)
			(effects
				(font
					(size 1.27 1.27)
				)
				(justify left bottom)
				(hide yes)
			)
		)
		(property "Dielectric" ""
			(at 327.66 184.15 0)
			(effects
				(font
					(size 1.27 1.27)
				)
				(justify left bottom)
				(hide yes)
			)
		)
		(pin "1"
		)
		(pin "2"
		)
		(instances
			(project "sdi-mipi-video-converter"
				(path ""
					(reference "C18")
					(unit 1)
				)
			)
		)
	)
	(symbol
		(lib_id "antmicroCapacitors0603:C_22u_0603")
		(at 388.62 52.07 90)
		(unit 1)
		(exclude_from_sim no)
		(in_bom yes)
		(on_board yes)
		(dnp no)
		(fields_autoplaced yes)
		(property "Reference" "C34"
			(at 391.16 48.2535 90)
			(effects
				(font
					(size 1.27 1.27)
					(thickness 0.15)
				)
				(justify right)
			)
		)
		(property "Value" "C_22u_0603"
			(at 398.78 31.75 0)
			(effects
				(font
					(size 1.27 1.27)
					(thickness 0.15)
				)
				(justify left bottom)
				(hide yes)
			)
		)
		(property "Footprint" "antmicro-footprints:C_0603_1608Metric"
			(at 401.32 31.75 0)
			(effects
				(font
					(size 1.27 1.27)
					(thickness 0.15)
				)
				(justify left bottom)
				(hide yes)
			)
		)
		(property "Datasheet" "https://www.murata.com/products/productdetail?partno=GRM188R60J226MEA0%23"
			(at 403.86 31.75 0)
			(effects
				(font
					(size 1.27 1.27)
					(thickness 0.15)
				)
				(justify left bottom)
				(hide yes)
			)
		)
		(property "Description" "SMD Multilayer Ceramic Capacitor, 22 µF, 6.3 V, 0603 [1608 Metric], ± 20%, X5R, GRM Series"
			(at 388.62 52.07 0)
			(effects
				(font
					(size 1.27 1.27)
				)
				(hide yes)
			)
		)
		(property "Manufacturer" "Murata"
			(at 408.94 31.75 0)
			(effects
				(font
					(size 1.27 1.27)
					(thickness 0.15)
				)
				(justify left bottom)
				(hide yes)
			)
		)
		(property "MPN" "GRM188R60J226MEA0D"
			(at 406.4 31.75 0)
			(effects
				(font
					(size 1.27 1.27)
					(thickness 0.15)
				)
				(justify left bottom)
				(hide yes)
			)
		)
		(property "Val" "22u"
			(at 391.16 50.7935 90)
			(effects
				(font
					(size 1.27 1.27)
					(thickness 0.15)
				)
				(justify right)
			)
		)
		(property "License" "Apache-2.0"
			(at 411.48 31.75 0)
			(effects
				(font
					(size 1.27 1.27)
					(thickness 0.15)
				)
				(justify left bottom)
				(hide yes)
			)
		)
		(property "Author" "Antmicro"
			(at 414.02 31.75 0)
			(effects
				(font
					(size 1.27 1.27)
					(thickness 0.15)
				)
				(justify left bottom)
				(hide yes)
			)
		)
		(property "Voltage" ""
			(at 416.56 31.75 0)
			(effects
				(font
					(size 1.27 1.27)
				)
				(justify left bottom)
				(hide yes)
			)
		)
		(property "Dielectric" ""
			(at 419.1 31.75 0)
			(effects
				(font
					(size 1.27 1.27)
				)
				(justify left bottom)
				(hide yes)
			)
		)
		(pin "1"
		)
		(pin "2"
		)
		(instances
			(project "sdi-mipi-video-converter"
				(path ""
					(reference "C34")
					(unit 1)
				)
			)
		)
	)
	(symbol
		(lib_id "antmicroTestPoints:TP_0.75mm_SMD")
		(at 285.75 44.45 180)
		(unit 1)
		(exclude_from_sim no)
		(in_bom yes)
		(on_board yes)
		(dnp no)
		(fields_autoplaced yes)
		(property "Reference" "TP12"
			(at 282.575 40.64 0)
			(effects
				(font
					(size 1.27 1.27)
					(thickness 0.15)
				)
			)
		)
		(property "Value" "TP_0.75mm_SMD"
			(at 267.97 36.83 0)
			(effects
				(font
					(size 1.27 1.27)
					(thickness 0.15)
				)
				(justify left bottom)
				(hide yes)
			)
		)
		(property "Footprint" "antmicro-footprints:TP_SMD_0.75mm"
			(at 267.97 34.29 0)
			(effects
				(font
					(size 1.27 1.27)
					(thickness 0.15)
				)
				(justify left bottom)
				(hide yes)
			)
		)
		(property "Datasheet" ""
			(at 267.97 31.75 0)
			(effects
				(font
					(size 1.27 1.27)
					(thickness 0.15)
				)
				(justify left bottom)
				(hide yes)
			)
		)
		(property "Description" "SMT test point"
			(at 285.75 44.45 0)
			(effects
				(font
					(size 1.27 1.27)
				)
				(hide yes)
			)
		)
		(property "MPN" ""
			(at 267.97 29.21 0)
			(effects
				(font
					(size 1.27 1.27)
					(thickness 0.15)
				)
				(justify left bottom)
				(hide yes)
			)
		)
		(property "Manufacturer" ""
			(at 267.97 26.67 0)
			(effects
				(font
					(size 1.27 1.27)
					(thickness 0.15)
				)
				(justify left bottom)
				(hide yes)
			)
		)
		(property "Author" "Antmicro"
			(at 267.97 24.13 0)
			(effects
				(font
					(size 1.27 1.27)
					(thickness 0.15)
				)
				(justify left bottom)
				(hide yes)
			)
		)
		(property "License" "Apache-2.0"
			(at 267.97 21.59 0)
			(effects
				(font
					(size 1.27 1.27)
					(thickness 0.15)
				)
				(justify left bottom)
				(hide yes)
			)
		)
		(pin "1"
		)
		(instances
			(project "sdi-mipi-video-converter"
				(path ""
					(reference "TP12")
					(unit 1)
				)
			)
		)
	)
	(symbol
		(lib_id "antmicroTestPoints:TP_0.75mm_SMD")
		(at 233.68 190.5 270)
		(unit 1)
		(exclude_from_sim no)
		(in_bom yes)
		(on_board yes)
		(dnp no)
		(fields_autoplaced yes)
		(property "Reference" "TP7"
			(at 236.22 193.675 90)
			(effects
				(font
					(size 1.27 1.27)
					(thickness 0.15)
				)
				(justify left)
			)
		)
		(property "Value" "TP_0.75mm_SMD"
			(at 226.06 208.28 0)
			(effects
				(font
					(size 1.27 1.27)
					(thickness 0.15)
				)
				(justify left bottom)
				(hide yes)
			)
		)
		(property "Footprint" "antmicro-footprints:TP_SMD_0.75mm"
			(at 223.52 208.28 0)
			(effects
				(font
					(size 1.27 1.27)
					(thickness 0.15)
				)
				(justify left bottom)
				(hide yes)
			)
		)
		(property "Datasheet" ""
			(at 220.98 208.28 0)
			(effects
				(font
					(size 1.27 1.27)
					(thickness 0.15)
				)
				(justify left bottom)
				(hide yes)
			)
		)
		(property "Description" "SMT test point"
			(at 233.68 190.5 0)
			(effects
				(font
					(size 1.27 1.27)
				)
				(hide yes)
			)
		)
		(property "MPN" ""
			(at 218.44 208.28 0)
			(effects
				(font
					(size 1.27 1.27)
					(thickness 0.15)
				)
				(justify left bottom)
				(hide yes)
			)
		)
		(property "Manufacturer" ""
			(at 215.9 208.28 0)
			(effects
				(font
					(size 1.27 1.27)
					(thickness 0.15)
				)
				(justify left bottom)
				(hide yes)
			)
		)
		(property "Author" "Antmicro"
			(at 213.36 208.28 0)
			(effects
				(font
					(size 1.27 1.27)
					(thickness 0.15)
				)
				(justify left bottom)
				(hide yes)
			)
		)
		(property "License" "Apache-2.0"
			(at 210.82 208.28 0)
			(effects
				(font
					(size 1.27 1.27)
					(thickness 0.15)
				)
				(justify left bottom)
				(hide yes)
			)
		)
		(pin "1"
		)
		(instances
			(project "sdi-mipi-video-converter"
				(path ""
					(reference "TP7")
					(unit 1)
				)
			)
		)
	)
	(symbol
		(lib_id "antmicroDCDCConverters:AP62301_TSOT")
		(at 289.56 39.37 0)
		(unit 1)
		(exclude_from_sim no)
		(in_bom yes)
		(on_board yes)
		(dnp no)
		(fields_autoplaced yes)
		(property "Reference" "U7"
			(at 299.72 31.75 0)
			(effects
				(font
					(size 1.27 1.27)
					(thickness 0.15)
				)
			)
		)
		(property "Value" "AP62301WU-7"
			(at 299.72 34.29 0)
			(effects
				(font
					(size 1.27 1.27)
					(thickness 0.15)
				)
			)
		)
		(property "Footprint" "antmicro-footprints:TSOT23-6"
			(at 325.12 36.83 0)
			(effects
				(font
					(size 1.27 1.27)
					(thickness 0.15)
				)
				(justify left bottom)
				(hide yes)
			)
		)
		(property "Datasheet" "https://www.diodes.com/assets/Datasheets/AP62300_AP62301_AP62300T.pdf"
			(at 325.12 39.37 0)
			(effects
				(font
					(size 1.27 1.27)
					(thickness 0.15)
				)
				(justify left bottom)
				(hide yes)
			)
		)
		(property "Description" "DC-DC Switching Synchronous Buck Regulator, Adjustable, 4.2V-18Vin, 0.8V-7V/3A out, TSOT-26-6"
			(at 289.56 39.37 0)
			(effects
				(font
					(size 1.27 1.27)
				)
				(hide yes)
			)
		)
		(property "MPN" "AP62301WU-7"
			(at 325.12 41.91 0)
			(effects
				(font
					(size 1.27 1.27)
					(thickness 0.15)
				)
				(justify left bottom)
				(hide yes)
			)
		)
		(property "Manufacturer" "Diodes Incorporated"
			(at 325.12 44.45 0)
			(effects
				(font
					(size 1.27 1.27)
					(thickness 0.15)
				)
				(justify left bottom)
				(hide yes)
			)
		)
		(property "Author" "Antmicro"
			(at 325.12 46.99 0)
			(effects
				(font
					(size 1.27 1.27)
					(thickness 0.15)
				)
				(justify left bottom)
				(hide yes)
			)
		)
		(property "License" "Apache-2.0"
			(at 325.12 49.53 0)
			(effects
				(font
					(size 1.27 1.27)
					(thickness 0.15)
				)
				(justify left bottom)
				(hide yes)
			)
		)
		(pin "1"
		)
		(pin "2"
		)
		(pin "3"
		)
		(pin "4"
		)
		(pin "5"
		)
		(pin "6"
		)
		(instances
			(project "sdi-mipi-video-converter"
				(path ""
					(reference "U7")
					(unit 1)
				)
			)
		)
	)
	(symbol
		(lib_id "antmicroCapacitors0603:C_1u_0603")
		(at 359.41 167.64 90)
		(unit 1)
		(exclude_from_sim no)
		(in_bom yes)
		(on_board yes)
		(dnp no)
		(fields_autoplaced yes)
		(property "Reference" "C29"
			(at 361.95 163.8235 90)
			(effects
				(font
					(size 1.27 1.27)
					(thickness 0.15)
				)
				(justify right)
			)
		)
		(property "Value" "C_1u_0603"
			(at 369.57 147.32 0)
			(effects
				(font
					(size 1.27 1.27)
					(thickness 0.15)
				)
				(justify left bottom)
				(hide yes)
			)
		)
		(property "Footprint" "antmicro-footprints:C_0603_1608Metric"
			(at 372.11 147.32 0)
			(effects
				(font
					(size 1.27 1.27)
					(thickness 0.15)
				)
				(justify left bottom)
				(hide yes)
			)
		)
		(property "Datasheet" "https://spicat.kyocera-avx.com/product/mlcc/chartview/0603YD105KAT2A/"
			(at 374.65 147.32 0)
			(effects
				(font
					(size 1.27 1.27)
					(thickness 0.15)
				)
				(justify left bottom)
				(hide yes)
			)
		)
		(property "Description" "SMD Multilayer Ceramic Capacitor, 1 µF, 16 V, 0603 [1608 Metric], ± 10%, X5R, AVX 0603 MLCC"
			(at 359.41 167.64 0)
			(effects
				(font
					(size 1.27 1.27)
				)
				(hide yes)
			)
		)
		(property "Manufacturer" "KYOCERA AVX"
			(at 379.73 147.32 0)
			(effects
				(font
					(size 1.27 1.27)
					(thickness 0.15)
				)
				(justify left bottom)
				(hide yes)
			)
		)
		(property "MPN" "0603YD105KAT2A"
			(at 377.19 147.32 0)
			(effects
				(font
					(size 1.27 1.27)
					(thickness 0.15)
				)
				(justify left bottom)
				(hide yes)
			)
		)
		(property "Val" "1u"
			(at 361.95 166.3635 90)
			(effects
				(font
					(size 1.27 1.27)
					(thickness 0.15)
				)
				(justify right)
			)
		)
		(property "License" "Apache-2.0"
			(at 382.27 147.32 0)
			(effects
				(font
					(size 1.27 1.27)
					(thickness 0.15)
				)
				(justify left bottom)
				(hide yes)
			)
		)
		(property "Author" "Antmicro"
			(at 384.81 147.32 0)
			(effects
				(font
					(size 1.27 1.27)
					(thickness 0.15)
				)
				(justify left bottom)
				(hide yes)
			)
		)
		(property "Voltage" ""
			(at 387.35 147.32 0)
			(effects
				(font
					(size 1.27 1.27)
				)
				(justify left bottom)
				(hide yes)
			)
		)
		(property "Dielectric" ""
			(at 389.89 147.32 0)
			(effects
				(font
					(size 1.27 1.27)
				)
				(justify left bottom)
				(hide yes)
			)
		)
		(pin "1"
		)
		(pin "2"
		)
		(instances
			(project "sdi-mipi-video-converter"
				(path ""
					(reference "C29")
					(unit 1)
				)
			)
		)
	)
	(symbol
		(lib_id "antmicroDCDCConverters:AP62301_TSOT")
		(at 288.29 105.41 0)
		(unit 1)
		(exclude_from_sim no)
		(in_bom yes)
		(on_board yes)
		(dnp no)
		(fields_autoplaced yes)
		(property "Reference" "U6"
			(at 298.45 97.79 0)
			(effects
				(font
					(size 1.27 1.27)
					(thickness 0.15)
				)
			)
		)
		(property "Value" "AP62301WU-7"
			(at 298.45 100.33 0)
			(effects
				(font
					(size 1.27 1.27)
					(thickness 0.15)
				)
			)
		)
		(property "Footprint" "antmicro-footprints:TSOT23-6"
			(at 323.85 102.87 0)
			(effects
				(font
					(size 1.27 1.27)
					(thickness 0.15)
				)
				(justify left bottom)
				(hide yes)
			)
		)
		(property "Datasheet" "https://www.diodes.com/assets/Datasheets/AP62300_AP62301_AP62300T.pdf"
			(at 323.85 105.41 0)
			(effects
				(font
					(size 1.27 1.27)
					(thickness 0.15)
				)
				(justify left bottom)
				(hide yes)
			)
		)
		(property "Description" "DC-DC Switching Synchronous Buck Regulator, Adjustable, 4.2V-18Vin, 0.8V-7V/3A out, TSOT-26-6"
			(at 288.29 105.41 0)
			(effects
				(font
					(size 1.27 1.27)
				)
				(hide yes)
			)
		)
		(property "MPN" "AP62301WU-7"
			(at 323.85 107.95 0)
			(effects
				(font
					(size 1.27 1.27)
					(thickness 0.15)
				)
				(justify left bottom)
				(hide yes)
			)
		)
		(property "Manufacturer" "Diodes Incorporated"
			(at 323.85 110.49 0)
			(effects
				(font
					(size 1.27 1.27)
					(thickness 0.15)
				)
				(justify left bottom)
				(hide yes)
			)
		)
		(property "Author" "Antmicro"
			(at 323.85 113.03 0)
			(effects
				(font
					(size 1.27 1.27)
					(thickness 0.15)
				)
				(justify left bottom)
				(hide yes)
			)
		)
		(property "License" "Apache-2.0"
			(at 323.85 115.57 0)
			(effects
				(font
					(size 1.27 1.27)
					(thickness 0.15)
				)
				(justify left bottom)
				(hide yes)
			)
		)
		(pin "1"
		)
		(pin "2"
		)
		(pin "3"
		)
		(pin "4"
		)
		(pin "5"
		)
		(pin "6"
		)
		(instances
			(project "sdi-mipi-video-converter"
				(path ""
					(reference "U6")
					(unit 1)
				)
			)
		)
	)
	(symbol
		(lib_id "antmicroResistors0402:R_10k_0402")
		(at 336.55 90.17 90)
		(unit 1)
		(exclude_from_sim no)
		(in_bom yes)
		(on_board yes)
		(dnp no)
		(fields_autoplaced yes)
		(property "Reference" "R23"
			(at 339.09 86.3599 90)
			(effects
				(font
					(size 1.27 1.27)
					(thickness 0.15)
				)
				(justify right)
			)
		)
		(property "Value" "R_10k_0402"
			(at 349.25 69.85 0)
			(effects
				(font
					(size 1.27 1.27)
					(thickness 0.15)
				)
				(justify left bottom)
				(hide yes)
			)
		)
		(property "Footprint" "antmicro-footprints:R_0402_1005Metric"
			(at 351.79 69.85 0)
			(effects
				(font
					(size 1.27 1.27)
					(thickness 0.15)
				)
				(justify left bottom)
				(hide yes)
			)
		)
		(property "Datasheet" "https://www.bourns.com/docs/product-datasheets/cr.pdf"
			(at 354.33 69.85 0)
			(effects
				(font
					(size 1.27 1.27)
					(thickness 0.15)
				)
				(justify left bottom)
				(hide yes)
			)
		)
		(property "Description" "SMD Chip Resistor, 10 kohm, ± 1%, 62.5 mW, 0402 [1005 Metric], Thick Film, General Purpose"
			(at 336.55 90.17 0)
			(effects
				(font
					(size 1.27 1.27)
				)
				(hide yes)
			)
		)
		(property "Manufacturer" "Bourns"
			(at 359.41 69.85 0)
			(effects
				(font
					(size 1.27 1.27)
					(thickness 0.15)
				)
				(justify left bottom)
				(hide yes)
			)
		)
		(property "MPN" "CR0402-FX-1002GLF"
			(at 356.87 69.85 0)
			(effects
				(font
					(size 1.27 1.27)
					(thickness 0.15)
				)
				(justify left bottom)
				(hide yes)
			)
		)
		(property "Val" "10k"
			(at 339.09 88.8999 90)
			(effects
				(font
					(size 1.27 1.27)
					(thickness 0.15)
				)
				(justify right)
			)
		)
		(property "License" "Apache-2.0"
			(at 361.95 69.85 0)
			(effects
				(font
					(size 1.27 1.27)
					(thickness 0.15)
				)
				(justify left bottom)
				(hide yes)
			)
		)
		(property "Author" "Antmicro"
			(at 364.49 69.85 0)
			(effects
				(font
					(size 1.27 1.27)
					(thickness 0.15)
				)
				(justify left bottom)
				(hide yes)
			)
		)
		(property "Tolerance" "1%"
			(at 346.71 69.85 0)
			(effects
				(font
					(size 1.27 1.27)
				)
				(justify left bottom)
				(hide yes)
			)
		)
		(pin "1"
		)
		(pin "2"
		)
		(instances
			(project "sdi-mipi-video-converter"
				(path ""
					(reference "R23")
					(unit 1)
				)
			)
		)
	)
	(symbol
		(lib_id "antmicropower:GND")
		(at 287.02 116.84 0)
		(unit 1)
		(exclude_from_sim no)
		(in_bom yes)
		(on_board yes)
		(dnp no)
		(fields_autoplaced yes)
		(property "Reference" "#PWR045"
			(at 295.91 119.38 0)
			(effects
				(font
					(size 1.27 1.27)
					(thickness 0.15)
				)
				(justify left bottom)
				(hide yes)
			)
		)
		(property "Value" "GND"
			(at 287.02 121.92 0)
			(effects
				(font
					(size 1.27 1.27)
					(thickness 0.15)
				)
			)
		)
		(property "Footprint" ""
			(at 295.91 124.46 0)
			(effects
				(font
					(size 1.27 1.27)
					(thickness 0.15)
				)
				(justify left bottom)
				(hide yes)
			)
		)
		(property "Datasheet" ""
			(at 295.91 129.54 0)
			(effects
				(font
					(size 1.27 1.27)
					(thickness 0.15)
				)
				(justify left bottom)
				(hide yes)
			)
		)
		(property "Description" ""
			(at 287.02 116.84 0)
			(effects
				(font
					(size 1.27 1.27)
				)
				(hide yes)
			)
		)
		(property "Author" "Antmicro"
			(at 295.91 124.46 0)
			(effects
				(font
					(size 1.27 1.27)
					(thickness 0.15)
				)
				(justify left bottom)
				(hide yes)
			)
		)
		(property "License" "Apache-2.0"
			(at 295.91 127 0)
			(effects
				(font
					(size 1.27 1.27)
					(thickness 0.15)
				)
				(justify left bottom)
				(hide yes)
			)
		)
		(pin "1"
		)
		(instances
			(project "sdi-mipi-video-converter"
				(path ""
					(reference "#PWR045")
					(unit 1)
				)
			)
		)
	)
	(symbol
		(lib_id "antmicroResistorsmisc:R_0R_0805")
		(at 266.7 105.41 180)
		(unit 1)
		(exclude_from_sim no)
		(in_bom yes)
		(on_board yes)
		(dnp no)
		(fields_autoplaced yes)
		(property "Reference" "R16"
			(at 264.16 99.06 0)
			(effects
				(font
					(size 1.27 1.27)
					(thickness 0.15)
				)
			)
		)
		(property "Value" "R_0R_0805"
			(at 246.38 92.71 0)
			(effects
				(font
					(size 1.27 1.27)
					(thickness 0.15)
				)
				(justify left bottom)
				(hide yes)
			)
		)
		(property "Footprint" "antmicro-footprints:R_0805_2012Metric"
			(at 246.38 90.17 0)
			(effects
				(font
					(size 1.27 1.27)
					(thickness 0.15)
				)
				(justify left bottom)
				(hide yes)
			)
		)
		(property "Datasheet" "https://www.vishay.com/docs/20035/dcrcwe3.pdf"
			(at 246.38 87.63 0)
			(effects
				(font
					(size 1.27 1.27)
					(thickness 0.15)
				)
				(justify left bottom)
				(hide yes)
			)
		)
		(property "Description" "Zero Ohm Resistor, Jumper, 0805 [2012 Metric], Thick Film, 125 mW, 2.5 A, Surface Mount Device"
			(at 266.7 105.41 0)
			(effects
				(font
					(size 1.27 1.27)
				)
				(hide yes)
			)
		)
		(property "Manufacturer" "Vishay"
			(at 246.38 82.55 0)
			(effects
				(font
					(size 1.27 1.27)
					(thickness 0.15)
				)
				(justify left bottom)
				(hide yes)
			)
		)
		(property "MPN" "CRCW08050000Z0EA"
			(at 246.38 85.09 0)
			(effects
				(font
					(size 1.27 1.27)
					(thickness 0.15)
				)
				(justify left bottom)
				(hide yes)
			)
		)
		(property "Val" "0R"
			(at 264.16 101.6 0)
			(effects
				(font
					(size 1.27 1.27)
					(thickness 0.15)
				)
			)
		)
		(property "License" "Apache-2.0"
			(at 246.38 80.01 0)
			(effects
				(font
					(size 1.27 1.27)
					(thickness 0.15)
				)
				(justify left bottom)
				(hide yes)
			)
		)
		(property "Author" "Antmicro"
			(at 246.38 77.47 0)
			(effects
				(font
					(size 1.27 1.27)
					(thickness 0.15)
				)
				(justify left bottom)
				(hide yes)
			)
		)
		(property "Tolerance" "~"
			(at 246.38 95.25 0)
			(effects
				(font
					(size 1.27 1.27)
				)
				(justify left bottom)
				(hide yes)
			)
		)
		(property "Current" "2.5A"
			(at 246.38 74.93 0)
			(effects
				(font
					(size 1.27 1.27)
					(thickness 0.15)
				)
				(justify left bottom)
				(hide yes)
			)
		)
		(pin "1"
		)
		(pin "2"
		)
		(instances
			(project "sdi-mipi-video-converter"
				(path ""
					(reference "R16")
					(unit 1)
				)
			)
		)
	)
	(symbol
		(lib_id "antmicroCapacitors0603:C_22u_0603")
		(at 388.62 118.11 90)
		(unit 1)
		(exclude_from_sim no)
		(in_bom yes)
		(on_board yes)
		(dnp no)
		(fields_autoplaced yes)
		(property "Reference" "C33"
			(at 391.16 114.2935 90)
			(effects
				(font
					(size 1.27 1.27)
					(thickness 0.15)
				)
				(justify right)
			)
		)
		(property "Value" "C_22u_0603"
			(at 398.78 97.79 0)
			(effects
				(font
					(size 1.27 1.27)
					(thickness 0.15)
				)
				(justify left bottom)
				(hide yes)
			)
		)
		(property "Footprint" "antmicro-footprints:C_0603_1608Metric"
			(at 401.32 97.79 0)
			(effects
				(font
					(size 1.27 1.27)
					(thickness 0.15)
				)
				(justify left bottom)
				(hide yes)
			)
		)
		(property "Datasheet" "https://www.murata.com/products/productdetail?partno=GRM188R60J226MEA0%23"
			(at 403.86 97.79 0)
			(effects
				(font
					(size 1.27 1.27)
					(thickness 0.15)
				)
				(justify left bottom)
				(hide yes)
			)
		)
		(property "Description" "SMD Multilayer Ceramic Capacitor, 22 µF, 6.3 V, 0603 [1608 Metric], ± 20%, X5R, GRM Series"
			(at 388.62 118.11 0)
			(effects
				(font
					(size 1.27 1.27)
				)
				(hide yes)
			)
		)
		(property "Manufacturer" "Murata"
			(at 408.94 97.79 0)
			(effects
				(font
					(size 1.27 1.27)
					(thickness 0.15)
				)
				(justify left bottom)
				(hide yes)
			)
		)
		(property "MPN" "GRM188R60J226MEA0D"
			(at 406.4 97.79 0)
			(effects
				(font
					(size 1.27 1.27)
					(thickness 0.15)
				)
				(justify left bottom)
				(hide yes)
			)
		)
		(property "Val" "22u"
			(at 391.16 116.8335 90)
			(effects
				(font
					(size 1.27 1.27)
					(thickness 0.15)
				)
				(justify right)
			)
		)
		(property "License" "Apache-2.0"
			(at 411.48 97.79 0)
			(effects
				(font
					(size 1.27 1.27)
					(thickness 0.15)
				)
				(justify left bottom)
				(hide yes)
			)
		)
		(property "Author" "Antmicro"
			(at 414.02 97.79 0)
			(effects
				(font
					(size 1.27 1.27)
					(thickness 0.15)
				)
				(justify left bottom)
				(hide yes)
			)
		)
		(property "Voltage" ""
			(at 416.56 97.79 0)
			(effects
				(font
					(size 1.27 1.27)
				)
				(justify left bottom)
				(hide yes)
			)
		)
		(property "Dielectric" ""
			(at 419.1 97.79 0)
			(effects
				(font
					(size 1.27 1.27)
				)
				(justify left bottom)
				(hide yes)
			)
		)
		(pin "1"
		)
		(pin "2"
		)
		(instances
			(project "sdi-mipi-video-converter"
				(path ""
					(reference "C33")
					(unit 1)
				)
			)
		)
	)
	(symbol
		(lib_id "antmicroCapacitors0603:C_22u_0603")
		(at 365.76 113.03 270)
		(unit 1)
		(exclude_from_sim no)
		(in_bom yes)
		(on_board yes)
		(dnp no)
		(fields_autoplaced yes)
		(property "Reference" "C24"
			(at 368.3 114.3062 90)
			(effects
				(font
					(size 1.27 1.27)
					(thickness 0.15)
				)
				(justify left)
			)
		)
		(property "Value" "C_22u_0603"
			(at 355.6 133.35 0)
			(effects
				(font
					(size 1.27 1.27)
					(thickness 0.15)
				)
				(justify left bottom)
				(hide yes)
			)
		)
		(property "Footprint" "antmicro-footprints:C_0603_1608Metric"
			(at 353.06 133.35 0)
			(effects
				(font
					(size 1.27 1.27)
					(thickness 0.15)
				)
				(justify left bottom)
				(hide yes)
			)
		)
		(property "Datasheet" "https://www.murata.com/products/productdetail?partno=GRM188R60J226MEA0%23"
			(at 350.52 133.35 0)
			(effects
				(font
					(size 1.27 1.27)
					(thickness 0.15)
				)
				(justify left bottom)
				(hide yes)
			)
		)
		(property "Description" "SMD Multilayer Ceramic Capacitor, 22 µF, 6.3 V, 0603 [1608 Metric], ± 20%, X5R, GRM Series"
			(at 365.76 113.03 0)
			(effects
				(font
					(size 1.27 1.27)
				)
				(hide yes)
			)
		)
		(property "Manufacturer" "Murata"
			(at 345.44 133.35 0)
			(effects
				(font
					(size 1.27 1.27)
					(thickness 0.15)
				)
				(justify left bottom)
				(hide yes)
			)
		)
		(property "MPN" "GRM188R60J226MEA0D"
			(at 347.98 133.35 0)
			(effects
				(font
					(size 1.27 1.27)
					(thickness 0.15)
				)
				(justify left bottom)
				(hide yes)
			)
		)
		(property "Val" "22u"
			(at 368.3 116.8462 90)
			(effects
				(font
					(size 1.27 1.27)
					(thickness 0.15)
				)
				(justify left)
			)
		)
		(property "License" "Apache-2.0"
			(at 342.9 133.35 0)
			(effects
				(font
					(size 1.27 1.27)
					(thickness 0.15)
				)
				(justify left bottom)
				(hide yes)
			)
		)
		(property "Author" "Antmicro"
			(at 340.36 133.35 0)
			(effects
				(font
					(size 1.27 1.27)
					(thickness 0.15)
				)
				(justify left bottom)
				(hide yes)
			)
		)
		(property "Voltage" ""
			(at 337.82 133.35 0)
			(effects
				(font
					(size 1.27 1.27)
				)
				(justify left bottom)
				(hide yes)
			)
		)
		(property "Dielectric" ""
			(at 335.28 133.35 0)
			(effects
				(font
					(size 1.27 1.27)
				)
				(justify left bottom)
				(hide yes)
			)
		)
		(pin "1"
		)
		(pin "2"
		)
		(instances
			(project "sdi-mipi-video-converter"
				(path ""
					(reference "C24")
					(unit 1)
				)
			)
		)
	)
	(symbol
		(lib_id "antmicroResistors0603:R_0R_0603")
		(at 349.25 156.21 0)
		(unit 1)
		(exclude_from_sim no)
		(in_bom yes)
		(on_board yes)
		(dnp no)
		(fields_autoplaced yes)
		(property "Reference" "R29"
			(at 351.79 149.86 0)
			(effects
				(font
					(size 1.27 1.27)
					(thickness 0.15)
				)
			)
		)
		(property "Value" "R_0R_0603"
			(at 369.57 168.91 0)
			(effects
				(font
					(size 1.27 1.27)
					(thickness 0.15)
				)
				(justify left bottom)
				(hide yes)
			)
		)
		(property "Footprint" "antmicro-footprints:R_0603_1608Metric"
			(at 369.57 171.45 0)
			(effects
				(font
					(size 1.27 1.27)
					(thickness 0.15)
				)
				(justify left bottom)
				(hide yes)
			)
		)
		(property "Datasheet" "https://www.bourns.com/docs/product-datasheets/cr.pdf?sfvrsn=574d41f6_14"
			(at 369.57 173.99 0)
			(effects
				(font
					(size 1.27 1.27)
					(thickness 0.15)
				)
				(justify left bottom)
				(hide yes)
			)
		)
		(property "Description" "Zero Ohm Resistor, Jumper, 0603 [1608 Metric], Thick Film, 100 mW, 1 A, Surface Mount Device, CR"
			(at 349.25 156.21 0)
			(effects
				(font
					(size 1.27 1.27)
				)
				(hide yes)
			)
		)
		(property "Manufacturer" "Bourns"
			(at 369.57 179.07 0)
			(effects
				(font
					(size 1.27 1.27)
					(thickness 0.15)
				)
				(justify left bottom)
				(hide yes)
			)
		)
		(property "MPN" "CR0603-J/-000ELF"
			(at 369.57 176.53 0)
			(effects
				(font
					(size 1.27 1.27)
					(thickness 0.15)
				)
				(justify left bottom)
				(hide yes)
			)
		)
		(property "Val" "0R"
			(at 351.79 152.4 0)
			(effects
				(font
					(size 1.27 1.27)
					(thickness 0.15)
				)
			)
		)
		(property "License" "Apache-2.0"
			(at 369.57 181.61 0)
			(effects
				(font
					(size 1.27 1.27)
					(thickness 0.15)
				)
				(justify left bottom)
				(hide yes)
			)
		)
		(property "Author" "Antmicro"
			(at 369.57 184.15 0)
			(effects
				(font
					(size 1.27 1.27)
					(thickness 0.15)
				)
				(justify left bottom)
				(hide yes)
			)
		)
		(property "Tolerance" "~"
			(at 369.57 166.37 0)
			(effects
				(font
					(size 1.27 1.27)
				)
				(justify left bottom)
				(hide yes)
			)
		)
		(property "Current" "1A"
			(at 369.57 186.69 0)
			(effects
				(font
					(size 1.27 1.27)
					(thickness 0.15)
				)
				(justify left bottom)
				(hide yes)
			)
		)
		(pin "1"
		)
		(pin "2"
		)
		(instances
			(project "sdi-mipi-video-converter"
				(path ""
					(reference "R29")
					(unit 1)
				)
			)
		)
	)
	(symbol
		(lib_id "antmicroResistorsmisc:R_0R_0805")
		(at 261.62 72.39 0)
		(unit 1)
		(exclude_from_sim no)
		(in_bom yes)
		(on_board yes)
		(dnp no)
		(fields_autoplaced yes)
		(property "Reference" "R15"
			(at 264.16 66.04 0)
			(effects
				(font
					(size 1.27 1.27)
					(thickness 0.15)
				)
			)
		)
		(property "Value" "R_0R_0805"
			(at 281.94 85.09 0)
			(effects
				(font
					(size 1.27 1.27)
					(thickness 0.15)
				)
				(justify left bottom)
				(hide yes)
			)
		)
		(property "Footprint" "antmicro-footprints:R_0805_2012Metric"
			(at 281.94 87.63 0)
			(effects
				(font
					(size 1.27 1.27)
					(thickness 0.15)
				)
				(justify left bottom)
				(hide yes)
			)
		)
		(property "Datasheet" "https://www.vishay.com/docs/20035/dcrcwe3.pdf"
			(at 281.94 90.17 0)
			(effects
				(font
					(size 1.27 1.27)
					(thickness 0.15)
				)
				(justify left bottom)
				(hide yes)
			)
		)
		(property "Description" "Zero Ohm Resistor, Jumper, 0805 [2012 Metric], Thick Film, 125 mW, 2.5 A, Surface Mount Device"
			(at 261.62 72.39 0)
			(effects
				(font
					(size 1.27 1.27)
				)
				(hide yes)
			)
		)
		(property "Manufacturer" "Vishay"
			(at 281.94 95.25 0)
			(effects
				(font
					(size 1.27 1.27)
					(thickness 0.15)
				)
				(justify left bottom)
				(hide yes)
			)
		)
		(property "MPN" "CRCW08050000Z0EA"
			(at 281.94 92.71 0)
			(effects
				(font
					(size 1.27 1.27)
					(thickness 0.15)
				)
				(justify left bottom)
				(hide yes)
			)
		)
		(property "Val" "0R"
			(at 264.16 68.58 0)
			(effects
				(font
					(size 1.27 1.27)
					(thickness 0.15)
				)
			)
		)
		(property "License" "Apache-2.0"
			(at 281.94 97.79 0)
			(effects
				(font
					(size 1.27 1.27)
					(thickness 0.15)
				)
				(justify left bottom)
				(hide yes)
			)
		)
		(property "Author" "Antmicro"
			(at 281.94 100.33 0)
			(effects
				(font
					(size 1.27 1.27)
					(thickness 0.15)
				)
				(justify left bottom)
				(hide yes)
			)
		)
		(property "Tolerance" "~"
			(at 281.94 82.55 0)
			(effects
				(font
					(size 1.27 1.27)
				)
				(justify left bottom)
				(hide yes)
			)
		)
		(property "Current" "2.5A"
			(at 281.94 102.87 0)
			(effects
				(font
					(size 1.27 1.27)
					(thickness 0.15)
				)
				(justify left bottom)
				(hide yes)
			)
		)
		(pin "1"
		)
		(pin "2"
		)
		(instances
			(project "sdi-mipi-video-converter"
				(path ""
					(reference "R15")
					(unit 1)
				)
			)
		)
	)
	(symbol
		(lib_id "antmicropower:+3.3V")
		(at 402.59 38.1 0)
		(unit 1)
		(exclude_from_sim no)
		(in_bom yes)
		(on_board yes)
		(dnp no)
		(fields_autoplaced yes)
		(property "Reference" "#PWR080"
			(at 402.59 41.91 0)
			(effects
				(font
					(size 1.27 1.27)
				)
				(hide yes)
			)
		)
		(property "Value" "+3V3"
			(at 402.59 33.02 0)
			(effects
				(font
					(size 1.27 1.27)
				)
			)
		)
		(property "Footprint" ""
			(at 402.59 38.1 0)
			(effects
				(font
					(size 1.27 1.27)
				)
				(hide yes)
			)
		)
		(property "Datasheet" ""
			(at 402.59 38.1 0)
			(effects
				(font
					(size 1.27 1.27)
				)
				(hide yes)
			)
		)
		(property "Description" ""
			(at 402.59 38.1 0)
			(effects
				(font
					(size 1.27 1.27)
				)
				(hide yes)
			)
		)
		(pin "1"
		)
		(instances
			(project "sdi-mipi-video-converter"
				(path ""
					(reference "#PWR080")
					(unit 1)
				)
			)
		)
	)
	(symbol
		(lib_id "antmicropower:GND")
		(at 101.6 204.47 0)
		(unit 1)
		(exclude_from_sim no)
		(in_bom yes)
		(on_board yes)
		(dnp no)
		(fields_autoplaced yes)
		(property "Reference" "#PWR08"
			(at 110.49 207.01 0)
			(effects
				(font
					(size 1.27 1.27)
					(thickness 0.15)
				)
				(justify left bottom)
				(hide yes)
			)
		)
		(property "Value" "GND"
			(at 101.6 209.55 0)
			(effects
				(font
					(size 1.27 1.27)
					(thickness 0.15)
				)
			)
		)
		(property "Footprint" ""
			(at 110.49 212.09 0)
			(effects
				(font
					(size 1.27 1.27)
					(thickness 0.15)
				)
				(justify left bottom)
				(hide yes)
			)
		)
		(property "Datasheet" ""
			(at 110.49 217.17 0)
			(effects
				(font
					(size 1.27 1.27)
					(thickness 0.15)
				)
				(justify left bottom)
				(hide yes)
			)
		)
		(property "Description" ""
			(at 101.6 204.47 0)
			(effects
				(font
					(size 1.27 1.27)
				)
				(hide yes)
			)
		)
		(property "Author" "Antmicro"
			(at 110.49 212.09 0)
			(effects
				(font
					(size 1.27 1.27)
					(thickness 0.15)
				)
				(justify left bottom)
				(hide yes)
			)
		)
		(property "License" "Apache-2.0"
			(at 110.49 214.63 0)
			(effects
				(font
					(size 1.27 1.27)
					(thickness 0.15)
				)
				(justify left bottom)
				(hide yes)
			)
		)
		(pin "1"
		)
		(instances
			(project "sdi-mipi-video-converter"
				(path ""
					(reference "#PWR08")
					(unit 1)
				)
			)
		)
	)
	(symbol
		(lib_id "antmicropower:GND")
		(at 71.12 207.01 0)
		(unit 1)
		(exclude_from_sim no)
		(in_bom yes)
		(on_board yes)
		(dnp no)
		(fields_autoplaced yes)
		(property "Reference" "#PWR04"
			(at 80.01 209.55 0)
			(effects
				(font
					(size 1.27 1.27)
					(thickness 0.15)
				)
				(justify left bottom)
				(hide yes)
			)
		)
		(property "Value" "GND"
			(at 71.12 212.09 0)
			(effects
				(font
					(size 1.27 1.27)
					(thickness 0.15)
				)
			)
		)
		(property "Footprint" ""
			(at 80.01 214.63 0)
			(effects
				(font
					(size 1.27 1.27)
					(thickness 0.15)
				)
				(justify left bottom)
				(hide yes)
			)
		)
		(property "Datasheet" ""
			(at 80.01 219.71 0)
			(effects
				(font
					(size 1.27 1.27)
					(thickness 0.15)
				)
				(justify left bottom)
				(hide yes)
			)
		)
		(property "Description" ""
			(at 71.12 207.01 0)
			(effects
				(font
					(size 1.27 1.27)
				)
				(hide yes)
			)
		)
		(property "Author" "Antmicro"
			(at 80.01 214.63 0)
			(effects
				(font
					(size 1.27 1.27)
					(thickness 0.15)
				)
				(justify left bottom)
				(hide yes)
			)
		)
		(property "License" "Apache-2.0"
			(at 80.01 217.17 0)
			(effects
				(font
					(size 1.27 1.27)
					(thickness 0.15)
				)
				(justify left bottom)
				(hide yes)
			)
		)
		(pin "1"
		)
		(instances
			(project "sdi-mipi-video-converter"
				(path ""
					(reference "#PWR04")
					(unit 1)
				)
			)
		)
	)
	(symbol
		(lib_id "antmicroCapacitors0402:C_100n_0402")
		(at 40.64 142.24 270)
		(unit 1)
		(exclude_from_sim no)
		(in_bom yes)
		(on_board yes)
		(dnp no)
		(property "Reference" "C3"
			(at 37.465 142.875 90)
			(effects
				(font
					(size 1.27 1.27)
					(thickness 0.15)
				)
				(justify left)
			)
		)
		(property "Value" "C_100n_0402"
			(at 30.48 162.56 0)
			(effects
				(font
					(size 1.27 1.27)
					(thickness 0.15)
				)
				(justify left bottom)
				(hide yes)
			)
		)
		(property "Footprint" "antmicro-footprints:C_0402_1005Metric"
			(at 27.94 162.56 0)
			(effects
				(font
					(size 1.27 1.27)
					(thickness 0.15)
				)
				(justify left bottom)
				(hide yes)
			)
		)
		(property "Datasheet" "https://www.murata.com/products/productdetail?partno=GRM155R61H104KE14%23"
			(at 25.4 162.56 0)
			(effects
				(font
					(size 1.27 1.27)
					(thickness 0.15)
				)
				(justify left bottom)
				(hide yes)
			)
		)
		(property "Description" "SMD Multilayer Ceramic Capacitor, 0.1 µF, 50 V, 0402 [1005 Metric], ± 10%, X5R, GRM Series"
			(at 40.64 142.24 0)
			(effects
				(font
					(size 1.27 1.27)
				)
				(hide yes)
			)
		)
		(property "Manufacturer" "Murata"
			(at 20.32 162.56 0)
			(effects
				(font
					(size 1.27 1.27)
					(thickness 0.15)
				)
				(justify left bottom)
				(hide yes)
			)
		)
		(property "MPN" "GRM155R61H104KE14D"
			(at 22.86 162.56 0)
			(effects
				(font
					(size 1.27 1.27)
					(thickness 0.15)
				)
				(justify left bottom)
				(hide yes)
			)
		)
		(property "Val" "100n"
			(at 34.925 146.685 90)
			(effects
				(font
					(size 1.27 1.27)
					(thickness 0.15)
				)
				(justify left)
			)
		)
		(property "License" "Apache-2.0"
			(at 17.78 162.56 0)
			(effects
				(font
					(size 1.27 1.27)
					(thickness 0.15)
				)
				(justify left bottom)
				(hide yes)
			)
		)
		(property "Author" "Antmicro"
			(at 15.24 162.56 0)
			(effects
				(font
					(size 1.27 1.27)
					(thickness 0.15)
				)
				(justify left bottom)
				(hide yes)
			)
		)
		(property "Voltage" "50V"
			(at 12.7 162.56 0)
			(effects
				(font
					(size 1.27 1.27)
				)
				(justify left bottom)
				(hide yes)
			)
		)
		(property "Dielectric" "X5R"
			(at 10.16 162.56 0)
			(effects
				(font
					(size 1.27 1.27)
				)
				(justify left bottom)
				(hide yes)
			)
		)
		(pin "1"
		)
		(pin "2"
		)
		(instances
			(project "sdi-mipi-video-converter"
				(path ""
					(reference "C3")
					(unit 1)
				)
			)
		)
	)
	(symbol
		(lib_id "antmicroResistorsmisc:R_0R_0805")
		(at 31.75 129.54 0)
		(unit 1)
		(exclude_from_sim no)
		(in_bom yes)
		(on_board yes)
		(dnp no)
		(property "Reference" "R5"
			(at 34.29 125.73 0)
			(effects
				(font
					(size 1.27 1.27)
					(thickness 0.15)
				)
			)
		)
		(property "Value" "R_0R_0805"
			(at 52.07 142.24 0)
			(effects
				(font
					(size 1.27 1.27)
					(thickness 0.15)
				)
				(justify left bottom)
				(hide yes)
			)
		)
		(property "Footprint" "antmicro-footprints:R_0805_2012Metric"
			(at 52.07 144.78 0)
			(effects
				(font
					(size 1.27 1.27)
					(thickness 0.15)
				)
				(justify left bottom)
				(hide yes)
			)
		)
		(property "Datasheet" "https://www.vishay.com/docs/20035/dcrcwe3.pdf"
			(at 52.07 147.32 0)
			(effects
				(font
					(size 1.27 1.27)
					(thickness 0.15)
				)
				(justify left bottom)
				(hide yes)
			)
		)
		(property "Description" "Zero Ohm Resistor, Jumper, 0805 [2012 Metric], Thick Film, 125 mW, 2.5 A, Surface Mount Device"
			(at 31.75 129.54 0)
			(effects
				(font
					(size 1.27 1.27)
				)
				(hide yes)
			)
		)
		(property "Manufacturer" "Vishay"
			(at 52.07 152.4 0)
			(effects
				(font
					(size 1.27 1.27)
					(thickness 0.15)
				)
				(justify left bottom)
				(hide yes)
			)
		)
		(property "MPN" "CRCW08050000Z0EA"
			(at 52.07 149.86 0)
			(effects
				(font
					(size 1.27 1.27)
					(thickness 0.15)
				)
				(justify left bottom)
				(hide yes)
			)
		)
		(property "Val" "0R"
			(at 34.29 127.635 0)
			(effects
				(font
					(size 1.27 1.27)
					(thickness 0.15)
				)
			)
		)
		(property "License" "Apache-2.0"
			(at 52.07 154.94 0)
			(effects
				(font
					(size 1.27 1.27)
					(thickness 0.15)
				)
				(justify left bottom)
				(hide yes)
			)
		)
		(property "Author" "Antmicro"
			(at 52.07 157.48 0)
			(effects
				(font
					(size 1.27 1.27)
					(thickness 0.15)
				)
				(justify left bottom)
				(hide yes)
			)
		)
		(property "Tolerance" "~"
			(at 52.07 139.7 0)
			(effects
				(font
					(size 1.27 1.27)
				)
				(justify left bottom)
				(hide yes)
			)
		)
		(property "Current" "2.5A"
			(at 52.07 160.02 0)
			(effects
				(font
					(size 1.27 1.27)
					(thickness 0.15)
				)
				(justify left bottom)
				(hide yes)
			)
		)
		(pin "1"
		)
		(pin "2"
		)
		(instances
			(project "sdi-mipi-video-converter"
				(path ""
					(reference "R5")
					(unit 1)
				)
			)
		)
	)
	(symbol
		(lib_id "antmicroOperationalAmplifiers:LM339_TSSOP_CUSTOM_Split")
		(at 154.94 270.51 0)
		(unit 3)
		(exclude_from_sim no)
		(in_bom yes)
		(on_board yes)
		(dnp no)
		(fields_autoplaced yes)
		(property "Reference" "U3"
			(at 160.02 264.16 0)
			(effects
				(font
					(size 1.27 1.27)
					(thickness 0.15)
				)
			)
		)
		(property "Value" "LM339_TSSOP_Split"
			(at 160.02 264.16 0)
			(effects
				(font
					(size 1.27 1.27)
					(thickness 0.15)
				)
				(hide yes)
			)
		)
		(property "Footprint" "antmicro-footprints:TSSOP-14_4.4x5mm_P0.65mm"
			(at 180.34 280.67 0)
			(effects
				(font
					(size 1.27 1.27)
					(thickness 0.15)
				)
				(justify left bottom)
				(hide yes)
			)
		)
		(property "Datasheet" "https://www.ti.com/lit/ds/symlink/lm339b.pdf?ts=1679641364820&ref_url=https%253A%252F%252Fwww.google.com%252F"
			(at 180.34 283.21 0)
			(effects
				(font
					(size 1.27 1.27)
					(thickness 0.15)
				)
				(justify left bottom)
				(hide yes)
			)
		)
		(property "Description" "Analogue Comparator, Differential, 4 Comparators, 300 ns, 2V to 36V, TSSOP, 14 Pins"
			(at 180.34 295.91 0)
			(effects
				(font
					(size 1.27 1.27)
				)
				(justify left bottom)
				(hide yes)
			)
		)
		(property "MPN" "LM339PW"
			(at 160.02 266.7 0)
			(effects
				(font
					(size 1.27 1.27)
					(thickness 0.15)
				)
			)
		)
		(property "Manufacturer" "Texas Instruments"
			(at 180.34 288.29 0)
			(effects
				(font
					(size 1.27 1.27)
					(thickness 0.15)
				)
				(justify left bottom)
				(hide yes)
			)
		)
		(property "Author" "Antmicro"
			(at 180.34 290.83 0)
			(effects
				(font
					(size 1.27 1.27)
					(thickness 0.15)
				)
				(justify left bottom)
				(hide yes)
			)
		)
		(property "License" "Apache-2.0"
			(at 180.34 293.37 0)
			(effects
				(font
					(size 1.27 1.27)
					(thickness 0.15)
				)
				(justify left bottom)
				(hide yes)
			)
		)
		(pin "2"
		)
		(pin "4"
		)
		(pin "5"
		)
		(pin "1"
		)
		(pin "6"
		)
		(pin "7"
		)
		(pin "14"
		)
		(pin "8"
		)
		(pin "9"
		)
		(pin "10"
		)
		(pin "11"
		)
		(pin "13"
		)
		(pin "12"
		)
		(pin "3"
		)
		(instances
			(project "sdi-mipi-video-converter"
				(path ""
					(reference "U3")
					(unit 3)
				)
			)
		)
	)
	(symbol
		(lib_id "antmicropower:+1V5")
		(at 27.94 127 0)
		(unit 1)
		(exclude_from_sim no)
		(in_bom yes)
		(on_board yes)
		(dnp no)
		(fields_autoplaced yes)
		(property "Reference" "#PWR0220"
			(at 27.94 130.81 0)
			(effects
				(font
					(size 1.27 1.27)
				)
				(hide yes)
			)
		)
		(property "Value" "+1V5"
			(at 27.94 121.92 0)
			(effects
				(font
					(size 1.27 1.27)
				)
			)
		)
		(property "Footprint" ""
			(at 27.94 127 0)
			(effects
				(font
					(size 1.27 1.27)
				)
				(hide yes)
			)
		)
		(property "Datasheet" ""
			(at 27.94 127 0)
			(effects
				(font
					(size 1.27 1.27)
				)
				(hide yes)
			)
		)
		(property "Description" ""
			(at 27.94 127 0)
			(effects
				(font
					(size 1.27 1.27)
				)
				(hide yes)
			)
		)
		(pin "1"
		)
		(instances
			(project "sdi-mipi-video-converter"
				(path ""
					(reference "#PWR0220")
					(unit 1)
				)
			)
		)
	)
	(symbol
		(lib_id "antmicropower:GND")
		(at 355.6 58.42 0)
		(unit 1)
		(exclude_from_sim no)
		(in_bom yes)
		(on_board yes)
		(dnp no)
		(fields_autoplaced yes)
		(property "Reference" "#PWR061"
			(at 364.49 60.96 0)
			(effects
				(font
					(size 1.27 1.27)
					(thickness 0.15)
				)
				(justify left bottom)
				(hide yes)
			)
		)
		(property "Value" "GND"
			(at 355.6 63.5 0)
			(effects
				(font
					(size 1.27 1.27)
					(thickness 0.15)
				)
			)
		)
		(property "Footprint" ""
			(at 364.49 66.04 0)
			(effects
				(font
					(size 1.27 1.27)
					(thickness 0.15)
				)
				(justify left bottom)
				(hide yes)
			)
		)
		(property "Datasheet" ""
			(at 364.49 71.12 0)
			(effects
				(font
					(size 1.27 1.27)
					(thickness 0.15)
				)
				(justify left bottom)
				(hide yes)
			)
		)
		(property "Description" ""
			(at 355.6 58.42 0)
			(effects
				(font
					(size 1.27 1.27)
				)
				(hide yes)
			)
		)
		(property "Author" "Antmicro"
			(at 364.49 66.04 0)
			(effects
				(font
					(size 1.27 1.27)
					(thickness 0.15)
				)
				(justify left bottom)
				(hide yes)
			)
		)
		(property "License" "Apache-2.0"
			(at 364.49 68.58 0)
			(effects
				(font
					(size 1.27 1.27)
					(thickness 0.15)
				)
				(justify left bottom)
				(hide yes)
			)
		)
		(pin "1"
		)
		(instances
			(project "sdi-mipi-video-converter"
				(path ""
					(reference "#PWR061")
					(unit 1)
				)
			)
		)
	)
	(symbol
		(lib_id "antmicroResistors0402:R_10k_0402")
		(at 345.44 173.99 90)
		(unit 1)
		(exclude_from_sim no)
		(in_bom yes)
		(on_board yes)
		(dnp no)
		(fields_autoplaced yes)
		(property "Reference" "R32"
			(at 347.98 170.1799 90)
			(effects
				(font
					(size 1.27 1.27)
					(thickness 0.15)
				)
				(justify right)
			)
		)
		(property "Value" "R_10k_0402"
			(at 358.14 153.67 0)
			(effects
				(font
					(size 1.27 1.27)
					(thickness 0.15)
				)
				(justify left bottom)
				(hide yes)
			)
		)
		(property "Footprint" "antmicro-footprints:R_0402_1005Metric"
			(at 360.68 153.67 0)
			(effects
				(font
					(size 1.27 1.27)
					(thickness 0.15)
				)
				(justify left bottom)
				(hide yes)
			)
		)
		(property "Datasheet" "https://www.bourns.com/docs/product-datasheets/cr.pdf"
			(at 363.22 153.67 0)
			(effects
				(font
					(size 1.27 1.27)
					(thickness 0.15)
				)
				(justify left bottom)
				(hide yes)
			)
		)
		(property "Description" "SMD Chip Resistor, 10 kohm, ± 1%, 62.5 mW, 0402 [1005 Metric], Thick Film, General Purpose"
			(at 345.44 173.99 0)
			(effects
				(font
					(size 1.27 1.27)
				)
				(hide yes)
			)
		)
		(property "Manufacturer" "Bourns"
			(at 368.3 153.67 0)
			(effects
				(font
					(size 1.27 1.27)
					(thickness 0.15)
				)
				(justify left bottom)
				(hide yes)
			)
		)
		(property "MPN" "CR0402-FX-1002GLF"
			(at 365.76 153.67 0)
			(effects
				(font
					(size 1.27 1.27)
					(thickness 0.15)
				)
				(justify left bottom)
				(hide yes)
			)
		)
		(property "Val" "10k"
			(at 347.98 172.7199 90)
			(effects
				(font
					(size 1.27 1.27)
					(thickness 0.15)
				)
				(justify right)
			)
		)
		(property "License" "Apache-2.0"
			(at 370.84 153.67 0)
			(effects
				(font
					(size 1.27 1.27)
					(thickness 0.15)
				)
				(justify left bottom)
				(hide yes)
			)
		)
		(property "Author" "Antmicro"
			(at 373.38 153.67 0)
			(effects
				(font
					(size 1.27 1.27)
					(thickness 0.15)
				)
				(justify left bottom)
				(hide yes)
			)
		)
		(property "Tolerance" "1%"
			(at 355.6 153.67 0)
			(effects
				(font
					(size 1.27 1.27)
				)
				(justify left bottom)
				(hide yes)
			)
		)
		(pin "1"
		)
		(pin "2"
		)
		(instances
			(project "sdi-mipi-video-converter"
				(path ""
					(reference "R32")
					(unit 1)
				)
			)
		)
	)
	(symbol
		(lib_id "antmicropower:GND")
		(at 99.06 143.51 0)
		(unit 1)
		(exclude_from_sim no)
		(in_bom yes)
		(on_board yes)
		(dnp no)
		(fields_autoplaced yes)
		(property "Reference" "#PWR0223"
			(at 107.95 146.05 0)
			(effects
				(font
					(size 1.27 1.27)
					(thickness 0.15)
				)
				(justify left bottom)
				(hide yes)
			)
		)
		(property "Value" "GND"
			(at 99.06 148.59 0)
			(effects
				(font
					(size 1.27 1.27)
					(thickness 0.15)
				)
			)
		)
		(property "Footprint" ""
			(at 107.95 151.13 0)
			(effects
				(font
					(size 1.27 1.27)
					(thickness 0.15)
				)
				(justify left bottom)
				(hide yes)
			)
		)
		(property "Datasheet" ""
			(at 107.95 156.21 0)
			(effects
				(font
					(size 1.27 1.27)
					(thickness 0.15)
				)
				(justify left bottom)
				(hide yes)
			)
		)
		(property "Description" ""
			(at 99.06 143.51 0)
			(effects
				(font
					(size 1.27 1.27)
				)
				(hide yes)
			)
		)
		(property "Author" "Antmicro"
			(at 107.95 151.13 0)
			(effects
				(font
					(size 1.27 1.27)
					(thickness 0.15)
				)
				(justify left bottom)
				(hide yes)
			)
		)
		(property "License" "Apache-2.0"
			(at 107.95 153.67 0)
			(effects
				(font
					(size 1.27 1.27)
					(thickness 0.15)
				)
				(justify left bottom)
				(hide yes)
			)
		)
		(pin "1"
		)
		(instances
			(project "sdi-mipi-video-converter"
				(path ""
					(reference "#PWR0223")
					(unit 1)
				)
			)
		)
	)
	(symbol
		(lib_id "antmicroCapacitors0603:C_10u_0603")
		(at 270.51 43.18 270)
		(unit 1)
		(exclude_from_sim no)
		(in_bom yes)
		(on_board yes)
		(dnp no)
		(fields_autoplaced yes)
		(property "Reference" "C13"
			(at 273.05 44.4562 90)
			(effects
				(font
					(size 1.27 1.27)
					(thickness 0.15)
				)
				(justify left)
			)
		)
		(property "Value" "C_10u_0603"
			(at 260.35 63.5 0)
			(effects
				(font
					(size 1.27 1.27)
					(thickness 0.15)
				)
				(justify left bottom)
				(hide yes)
			)
		)
		(property "Footprint" "antmicro-footprints:C_0603_1608Metric"
			(at 257.81 63.5 0)
			(effects
				(font
					(size 1.27 1.27)
					(thickness 0.15)
				)
				(justify left bottom)
				(hide yes)
			)
		)
		(property "Datasheet" "https://www.murata.com/products/productdetail?partno=GRM188R61A106KE69%23"
			(at 255.27 63.5 0)
			(effects
				(font
					(size 1.27 1.27)
					(thickness 0.15)
				)
				(justify left bottom)
				(hide yes)
			)
		)
		(property "Description" "SMD Multilayer Ceramic Capacitor, 10 µF, 10 V, 0603 [1608 Metric], ± 10%, X5R, GRM Series"
			(at 270.51 43.18 0)
			(effects
				(font
					(size 1.27 1.27)
				)
				(hide yes)
			)
		)
		(property "Manufacturer" "Murata"
			(at 250.19 63.5 0)
			(effects
				(font
					(size 1.27 1.27)
					(thickness 0.15)
				)
				(justify left bottom)
				(hide yes)
			)
		)
		(property "MPN" "GRM188R61A106KE69D"
			(at 252.73 63.5 0)
			(effects
				(font
					(size 1.27 1.27)
					(thickness 0.15)
				)
				(justify left bottom)
				(hide yes)
			)
		)
		(property "Val" "10u"
			(at 273.05 46.9962 90)
			(effects
				(font
					(size 1.27 1.27)
					(thickness 0.15)
				)
				(justify left)
			)
		)
		(property "License" "Apache-2.0"
			(at 247.65 63.5 0)
			(effects
				(font
					(size 1.27 1.27)
					(thickness 0.15)
				)
				(justify left bottom)
				(hide yes)
			)
		)
		(property "Author" "Antmicro"
			(at 245.11 63.5 0)
			(effects
				(font
					(size 1.27 1.27)
					(thickness 0.15)
				)
				(justify left bottom)
				(hide yes)
			)
		)
		(property "Voltage" ""
			(at 242.57 63.5 0)
			(effects
				(font
					(size 1.27 1.27)
				)
				(justify left bottom)
				(hide yes)
			)
		)
		(property "Dielectric" "template_dielectric"
			(at 240.03 63.5 0)
			(effects
				(font
					(size 1.27 1.27)
				)
				(justify left bottom)
				(hide yes)
			)
		)
		(pin "1"
		)
		(pin "2"
		)
		(instances
			(project "sdi-mipi-video-converter"
				(path ""
					(reference "C13")
					(unit 1)
				)
			)
		)
	)
	(symbol
		(lib_id "antmicroFixedInductors:L_3u3_6.6A_XEL4030")
		(at 325.12 72.39 0)
		(unit 1)
		(exclude_from_sim no)
		(in_bom yes)
		(on_board yes)
		(dnp no)
		(fields_autoplaced yes)
		(property "Reference" "L1"
			(at 327.66 67.31 0)
			(effects
				(font
					(size 1.27 1.27)
					(thickness 0.15)
				)
			)
		)
		(property "Value" "L_3u3_5.9A_XEL4030"
			(at 339.09 74.93 0)
			(effects
				(font
					(size 1.27 1.27)
					(thickness 0.15)
				)
				(justify left bottom)
				(hide yes)
			)
		)
		(property "Footprint" "antmicro-footprints:L_Coilcraft-XEL4030"
			(at 339.09 80.01 0)
			(effects
				(font
					(size 1.27 1.27)
					(thickness 0.15)
				)
				(justify left bottom)
				(hide yes)
			)
		)
		(property "Datasheet" "https://www.coilcraft.com/getmedia/8245f050-f190-4295-8c41-7c03d662ee3d/xel4030.pdf"
			(at 339.09 82.55 0)
			(effects
				(font
					(size 1.27 1.27)
					(thickness 0.15)
				)
				(justify left bottom)
				(hide yes)
			)
		)
		(property "Description" "Power Inductor (SMT), AEC-Q200, 3.3 µH, 6.6 A, Shielded, 5.9 A, XEL4030"
			(at 325.12 72.39 0)
			(effects
				(font
					(size 1.27 1.27)
				)
				(hide yes)
			)
		)
		(property "MPN" "XEL4030-332MEC"
			(at 339.09 87.63 0)
			(effects
				(font
					(size 1.27 1.27)
					(thickness 0.15)
				)
				(justify left bottom)
				(hide yes)
			)
		)
		(property "Manufacturer" "Coilcraft"
			(at 339.09 85.09 0)
			(effects
				(font
					(size 1.27 1.27)
					(thickness 0.15)
				)
				(justify left bottom)
				(hide yes)
			)
		)
		(property "Val" "3u3/6.6A"
			(at 327.66 69.85 0)
			(effects
				(font
					(size 1.27 1.27)
					(thickness 0.15)
				)
			)
		)
		(property "Size" "4.0x4.0"
			(at 339.09 95.25 0)
			(effects
				(font
					(size 1.27 1.27)
					(thickness 0.15)
				)
				(justify left bottom)
				(hide yes)
			)
		)
		(property "ISat" "5.9 A"
			(at 339.09 88.9 0)
			(effects
				(font
					(size 1.27 1.27)
				)
				(justify left)
				(hide yes)
			)
		)
		(property "IMax" "6.6 A"
			(at 339.09 92.71 0)
			(effects
				(font
					(size 1.27 1.27)
					(thickness 0.15)
				)
				(justify left bottom)
				(hide yes)
			)
		)
		(property "Author" "Antmicro"
			(at 339.09 97.79 0)
			(effects
				(font
					(size 1.27 1.27)
					(thickness 0.15)
				)
				(justify left bottom)
				(hide yes)
			)
		)
		(property "License" "Apache-2.0"
			(at 339.09 100.33 0)
			(effects
				(font
					(size 1.27 1.27)
					(thickness 0.15)
				)
				(justify left bottom)
				(hide yes)
			)
		)
		(pin "1"
		)
		(pin "2"
		)
		(instances
			(project "sdi-mipi-video-converter"
				(path ""
					(reference "L1")
					(unit 1)
				)
			)
		)
	)
	(symbol
		(lib_id "antmicroLEDIndicationDiscrete:LED_G_0603_LTST-C190GKT")
		(at 218.44 259.08 270)
		(mirror x)
		(unit 1)
		(exclude_from_sim no)
		(in_bom yes)
		(on_board yes)
		(dnp no)
		(fields_autoplaced yes)
		(property "Reference" "D1"
			(at 215.9 255.27 90)
			(effects
				(font
					(size 1.27 1.27)
					(thickness 0.15)
				)
				(justify right)
			)
		)
		(property "Value" "LED_G_0603_LTST-C190GKT"
			(at 215.9 257.81 90)
			(effects
				(font
					(size 1.27 1.27)
					(thickness 0.15)
				)
				(justify right)
			)
		)
		(property "Footprint" "antmicro-footprints:LED_0603_1608Metric_G"
			(at 208.28 236.22 0)
			(effects
				(font
					(size 1.27 1.27)
					(thickness 0.15)
				)
				(justify left bottom)
				(hide yes)
			)
		)
		(property "Datasheet" "https://media.digikey.com/pdf/Data%20Sheets/Lite-On%20PDFs/LTST-C190GKT.pdf"
			(at 205.74 236.22 0)
			(effects
				(font
					(size 1.27 1.27)
					(thickness 0.15)
				)
				(justify left bottom)
				(hide yes)
			)
		)
		(property "Description" "LED, Green, SMD, 0603, 20 mA, 2.1 V, 569 nm"
			(at 218.44 259.08 0)
			(effects
				(font
					(size 1.27 1.27)
				)
				(hide yes)
			)
		)
		(property "MPN" "LTST-C190GKT"
			(at 203.2 236.22 0)
			(effects
				(font
					(size 1.27 1.27)
					(thickness 0.15)
				)
				(justify left bottom)
				(hide yes)
			)
		)
		(property "Manufacturer" "Lite-On"
			(at 200.66 236.22 0)
			(effects
				(font
					(size 1.27 1.27)
					(thickness 0.15)
				)
				(justify left bottom)
				(hide yes)
			)
		)
		(property "Author" "Antmicro"
			(at 198.12 236.22 0)
			(effects
				(font
					(size 1.27 1.27)
					(thickness 0.15)
				)
				(justify left bottom)
				(hide yes)
			)
		)
		(property "License" "Apache-2.0"
			(at 195.58 236.22 0)
			(effects
				(font
					(size 1.27 1.27)
					(thickness 0.15)
				)
				(justify left bottom)
				(hide yes)
			)
		)
		(property "Color" "Green"
			(at 215.9 259.0799 90)
			(effects
				(font
					(size 1.27 1.27)
				)
				(justify right)
				(hide yes)
			)
		)
		(pin "1"
		)
		(pin "2"
		)
		(instances
			(project "sdi-mipi-video-converter"
				(path ""
					(reference "D1")
					(unit 1)
				)
			)
		)
	)
	(symbol
		(lib_id "antmicropower:GND")
		(at 91.44 62.23 0)
		(unit 1)
		(exclude_from_sim no)
		(in_bom yes)
		(on_board yes)
		(dnp no)
		(fields_autoplaced yes)
		(property "Reference" "#PWR0219"
			(at 100.33 64.77 0)
			(effects
				(font
					(size 1.27 1.27)
					(thickness 0.15)
				)
				(justify left bottom)
				(hide yes)
			)
		)
		(property "Value" "GND"
			(at 91.44 67.31 0)
			(effects
				(font
					(size 1.27 1.27)
					(thickness 0.15)
				)
			)
		)
		(property "Footprint" ""
			(at 100.33 69.85 0)
			(effects
				(font
					(size 1.27 1.27)
					(thickness 0.15)
				)
				(justify left bottom)
				(hide yes)
			)
		)
		(property "Datasheet" ""
			(at 100.33 74.93 0)
			(effects
				(font
					(size 1.27 1.27)
					(thickness 0.15)
				)
				(justify left bottom)
				(hide yes)
			)
		)
		(property "Description" ""
			(at 91.44 62.23 0)
			(effects
				(font
					(size 1.27 1.27)
				)
				(hide yes)
			)
		)
		(property "Author" "Antmicro"
			(at 100.33 69.85 0)
			(effects
				(font
					(size 1.27 1.27)
					(thickness 0.15)
				)
				(justify left bottom)
				(hide yes)
			)
		)
		(property "License" "Apache-2.0"
			(at 100.33 72.39 0)
			(effects
				(font
					(size 1.27 1.27)
					(thickness 0.15)
				)
				(justify left bottom)
				(hide yes)
			)
		)
		(pin "1"
		)
		(instances
			(project "sdi-mipi-video-converter"
				(path ""
					(reference "#PWR0219")
					(unit 1)
				)
			)
		)
	)
	(symbol
		(lib_id "antmicroOperationalAmplifiers:LM339_TSSOP_CUSTOM_Split")
		(at 86.36 231.14 0)
		(unit 1)
		(exclude_from_sim no)
		(in_bom yes)
		(on_board yes)
		(dnp no)
		(fields_autoplaced yes)
		(property "Reference" "U2"
			(at 91.44 224.79 0)
			(effects
				(font
					(size 1.27 1.27)
					(thickness 0.15)
				)
			)
		)
		(property "Value" "LM339_TSSOP_Split"
			(at 91.44 224.79 0)
			(effects
				(font
					(size 1.27 1.27)
					(thickness 0.15)
				)
				(hide yes)
			)
		)
		(property "Footprint" "antmicro-footprints:TSSOP-14_4.4x5mm_P0.65mm"
			(at 111.76 241.3 0)
			(effects
				(font
					(size 1.27 1.27)
					(thickness 0.15)
				)
				(justify left bottom)
				(hide yes)
			)
		)
		(property "Datasheet" "https://www.ti.com/lit/ds/symlink/lm339b.pdf?ts=1679641364820&ref_url=https%253A%252F%252Fwww.google.com%252F"
			(at 111.76 243.84 0)
			(effects
				(font
					(size 1.27 1.27)
					(thickness 0.15)
				)
				(justify left bottom)
				(hide yes)
			)
		)
		(property "Description" "Analogue Comparator, Differential, 4 Comparators, 300 ns, 2V to 36V, TSSOP, 14 Pins"
			(at 111.76 256.54 0)
			(effects
				(font
					(size 1.27 1.27)
				)
				(justify left bottom)
				(hide yes)
			)
		)
		(property "MPN" "LM339PW"
			(at 91.44 227.33 0)
			(effects
				(font
					(size 1.27 1.27)
					(thickness 0.15)
				)
			)
		)
		(property "Manufacturer" "Texas Instruments"
			(at 111.76 248.92 0)
			(effects
				(font
					(size 1.27 1.27)
					(thickness 0.15)
				)
				(justify left bottom)
				(hide yes)
			)
		)
		(property "Author" "Antmicro"
			(at 111.76 251.46 0)
			(effects
				(font
					(size 1.27 1.27)
					(thickness 0.15)
				)
				(justify left bottom)
				(hide yes)
			)
		)
		(property "License" "Apache-2.0"
			(at 111.76 254 0)
			(effects
				(font
					(size 1.27 1.27)
					(thickness 0.15)
				)
				(justify left bottom)
				(hide yes)
			)
		)
		(pin "2"
		)
		(pin "4"
		)
		(pin "5"
		)
		(pin "1"
		)
		(pin "6"
		)
		(pin "7"
		)
		(pin "14"
		)
		(pin "8"
		)
		(pin "9"
		)
		(pin "10"
		)
		(pin "11"
		)
		(pin "13"
		)
		(pin "12"
		)
		(pin "3"
		)
		(instances
			(project "sdi-mipi-video-converter"
				(path ""
					(reference "U2")
					(unit 1)
				)
			)
		)
	)
	(symbol
		(lib_id "antmicropower:GND")
		(at 218.44 267.97 0)
		(unit 1)
		(exclude_from_sim no)
		(in_bom yes)
		(on_board yes)
		(dnp no)
		(fields_autoplaced yes)
		(property "Reference" "#PWR033"
			(at 227.33 270.51 0)
			(effects
				(font
					(size 1.27 1.27)
					(thickness 0.15)
				)
				(justify left bottom)
				(hide yes)
			)
		)
		(property "Value" "GND"
			(at 218.44 273.05 0)
			(effects
				(font
					(size 1.27 1.27)
					(thickness 0.15)
				)
			)
		)
		(property "Footprint" ""
			(at 227.33 275.59 0)
			(effects
				(font
					(size 1.27 1.27)
					(thickness 0.15)
				)
				(justify left bottom)
				(hide yes)
			)
		)
		(property "Datasheet" ""
			(at 227.33 280.67 0)
			(effects
				(font
					(size 1.27 1.27)
					(thickness 0.15)
				)
				(justify left bottom)
				(hide yes)
			)
		)
		(property "Description" ""
			(at 218.44 267.97 0)
			(effects
				(font
					(size 1.27 1.27)
				)
				(hide yes)
			)
		)
		(property "Author" "Antmicro"
			(at 227.33 275.59 0)
			(effects
				(font
					(size 1.27 1.27)
					(thickness 0.15)
				)
				(justify left bottom)
				(hide yes)
			)
		)
		(property "License" "Apache-2.0"
			(at 227.33 278.13 0)
			(effects
				(font
					(size 1.27 1.27)
					(thickness 0.15)
				)
				(justify left bottom)
				(hide yes)
			)
		)
		(pin "1"
		)
		(instances
			(project "sdi-mipi-video-converter"
				(path ""
					(reference "#PWR033")
					(unit 1)
				)
			)
		)
	)
	(symbol
		(lib_id "antmicroCapacitors0603:C_22u_0603")
		(at 367.03 85.09 90)
		(unit 1)
		(exclude_from_sim no)
		(in_bom yes)
		(on_board yes)
		(dnp no)
		(fields_autoplaced yes)
		(property "Reference" "C23"
			(at 369.57 81.2735 90)
			(effects
				(font
					(size 1.27 1.27)
					(thickness 0.15)
				)
				(justify right)
			)
		)
		(property "Value" "C_22u_0603"
			(at 377.19 64.77 0)
			(effects
				(font
					(size 1.27 1.27)
					(thickness 0.15)
				)
				(justify left bottom)
				(hide yes)
			)
		)
		(property "Footprint" "antmicro-footprints:C_0603_1608Metric"
			(at 379.73 64.77 0)
			(effects
				(font
					(size 1.27 1.27)
					(thickness 0.15)
				)
				(justify left bottom)
				(hide yes)
			)
		)
		(property "Datasheet" "https://www.murata.com/products/productdetail?partno=GRM188R60J226MEA0%23"
			(at 382.27 64.77 0)
			(effects
				(font
					(size 1.27 1.27)
					(thickness 0.15)
				)
				(justify left bottom)
				(hide yes)
			)
		)
		(property "Description" "SMD Multilayer Ceramic Capacitor, 22 µF, 6.3 V, 0603 [1608 Metric], ± 20%, X5R, GRM Series"
			(at 367.03 85.09 0)
			(effects
				(font
					(size 1.27 1.27)
				)
				(hide yes)
			)
		)
		(property "Manufacturer" "Murata"
			(at 387.35 64.77 0)
			(effects
				(font
					(size 1.27 1.27)
					(thickness 0.15)
				)
				(justify left bottom)
				(hide yes)
			)
		)
		(property "MPN" "GRM188R60J226MEA0D"
			(at 384.81 64.77 0)
			(effects
				(font
					(size 1.27 1.27)
					(thickness 0.15)
				)
				(justify left bottom)
				(hide yes)
			)
		)
		(property "Val" "22u"
			(at 369.57 83.8135 90)
			(effects
				(font
					(size 1.27 1.27)
					(thickness 0.15)
				)
				(justify right)
			)
		)
		(property "License" "Apache-2.0"
			(at 389.89 64.77 0)
			(effects
				(font
					(size 1.27 1.27)
					(thickness 0.15)
				)
				(justify left bottom)
				(hide yes)
			)
		)
		(property "Author" "Antmicro"
			(at 392.43 64.77 0)
			(effects
				(font
					(size 1.27 1.27)
					(thickness 0.15)
				)
				(justify left bottom)
				(hide yes)
			)
		)
		(property "Voltage" ""
			(at 394.97 64.77 0)
			(effects
				(font
					(size 1.27 1.27)
				)
				(justify left bottom)
				(hide yes)
			)
		)
		(property "Dielectric" ""
			(at 397.51 64.77 0)
			(effects
				(font
					(size 1.27 1.27)
				)
				(justify left bottom)
				(hide yes)
			)
		)
		(pin "1"
		)
		(pin "2"
		)
		(instances
			(project "sdi-mipi-video-converter"
				(path ""
					(reference "C23")
					(unit 1)
				)
			)
		)
	)
	(symbol
		(lib_id "antmicropower:GND")
		(at 297.18 240.03 0)
		(unit 1)
		(exclude_from_sim no)
		(in_bom yes)
		(on_board yes)
		(dnp no)
		(fields_autoplaced yes)
		(property "Reference" "#PWR052"
			(at 306.07 242.57 0)
			(effects
				(font
					(size 1.27 1.27)
					(thickness 0.15)
				)
				(justify left bottom)
				(hide yes)
			)
		)
		(property "Value" "GND"
			(at 297.18 245.11 0)
			(effects
				(font
					(size 1.27 1.27)
					(thickness 0.15)
				)
			)
		)
		(property "Footprint" ""
			(at 306.07 247.65 0)
			(effects
				(font
					(size 1.27 1.27)
					(thickness 0.15)
				)
				(justify left bottom)
				(hide yes)
			)
		)
		(property "Datasheet" ""
			(at 306.07 252.73 0)
			(effects
				(font
					(size 1.27 1.27)
					(thickness 0.15)
				)
				(justify left bottom)
				(hide yes)
			)
		)
		(property "Description" ""
			(at 297.18 240.03 0)
			(effects
				(font
					(size 1.27 1.27)
				)
				(hide yes)
			)
		)
		(property "Author" "Antmicro"
			(at 306.07 247.65 0)
			(effects
				(font
					(size 1.27 1.27)
					(thickness 0.15)
				)
				(justify left bottom)
				(hide yes)
			)
		)
		(property "License" "Apache-2.0"
			(at 306.07 250.19 0)
			(effects
				(font
					(size 1.27 1.27)
					(thickness 0.15)
				)
				(justify left bottom)
				(hide yes)
			)
		)
		(pin "1"
		)
		(instances
			(project "sdi-mipi-video-converter"
				(path ""
					(reference "#PWR052")
					(unit 1)
				)
			)
		)
	)
	(symbol
		(lib_id "antmicroTestPoints:TP_0.75mm_SMD")
		(at 240.03 190.5 270)
		(unit 1)
		(exclude_from_sim no)
		(in_bom yes)
		(on_board yes)
		(dnp no)
		(fields_autoplaced yes)
		(property "Reference" "TP8"
			(at 242.57 193.675 90)
			(effects
				(font
					(size 1.27 1.27)
					(thickness 0.15)
				)
				(justify left)
			)
		)
		(property "Value" "TP_0.75mm_SMD"
			(at 232.41 208.28 0)
			(effects
				(font
					(size 1.27 1.27)
					(thickness 0.15)
				)
				(justify left bottom)
				(hide yes)
			)
		)
		(property "Footprint" "antmicro-footprints:TP_SMD_0.75mm"
			(at 229.87 208.28 0)
			(effects
				(font
					(size 1.27 1.27)
					(thickness 0.15)
				)
				(justify left bottom)
				(hide yes)
			)
		)
		(property "Datasheet" ""
			(at 227.33 208.28 0)
			(effects
				(font
					(size 1.27 1.27)
					(thickness 0.15)
				)
				(justify left bottom)
				(hide yes)
			)
		)
		(property "Description" "SMT test point"
			(at 240.03 190.5 0)
			(effects
				(font
					(size 1.27 1.27)
				)
				(hide yes)
			)
		)
		(property "MPN" ""
			(at 224.79 208.28 0)
			(effects
				(font
					(size 1.27 1.27)
					(thickness 0.15)
				)
				(justify left bottom)
				(hide yes)
			)
		)
		(property "Manufacturer" ""
			(at 222.25 208.28 0)
			(effects
				(font
					(size 1.27 1.27)
					(thickness 0.15)
				)
				(justify left bottom)
				(hide yes)
			)
		)
		(property "Author" "Antmicro"
			(at 219.71 208.28 0)
			(effects
				(font
					(size 1.27 1.27)
					(thickness 0.15)
				)
				(justify left bottom)
				(hide yes)
			)
		)
		(property "License" "Apache-2.0"
			(at 217.17 208.28 0)
			(effects
				(font
					(size 1.27 1.27)
					(thickness 0.15)
				)
				(justify left bottom)
				(hide yes)
			)
		)
		(pin "1"
		)
		(instances
			(project "sdi-mipi-video-converter"
				(path ""
					(reference "TP8")
					(unit 1)
				)
			)
		)
	)
	(symbol
		(lib_id "antmicroOperationalAmplifiers:LM339_TSSOP_CUSTOM_Split")
		(at 86.36 270.51 0)
		(unit 1)
		(exclude_from_sim no)
		(in_bom yes)
		(on_board yes)
		(dnp no)
		(fields_autoplaced yes)
		(property "Reference" "U3"
			(at 91.44 276.86 0)
			(effects
				(font
					(size 1.27 1.27)
					(thickness 0.15)
				)
			)
		)
		(property "Value" "LM339_TSSOP_Split"
			(at 91.44 264.16 0)
			(effects
				(font
					(size 1.27 1.27)
					(thickness 0.15)
				)
				(hide yes)
			)
		)
		(property "Footprint" "antmicro-footprints:TSSOP-14_4.4x5mm_P0.65mm"
			(at 111.76 280.67 0)
			(effects
				(font
					(size 1.27 1.27)
					(thickness 0.15)
				)
				(justify left bottom)
				(hide yes)
			)
		)
		(property "Datasheet" "https://www.ti.com/lit/ds/symlink/lm339b.pdf?ts=1679641364820&ref_url=https%253A%252F%252Fwww.google.com%252F"
			(at 111.76 283.21 0)
			(effects
				(font
					(size 1.27 1.27)
					(thickness 0.15)
				)
				(justify left bottom)
				(hide yes)
			)
		)
		(property "Description" "Analogue Comparator, Differential, 4 Comparators, 300 ns, 2V to 36V, TSSOP, 14 Pins"
			(at 111.76 295.91 0)
			(effects
				(font
					(size 1.27 1.27)
				)
				(justify left bottom)
				(hide yes)
			)
		)
		(property "MPN" "LM339PW"
			(at 91.44 279.4 0)
			(effects
				(font
					(size 1.27 1.27)
					(thickness 0.15)
				)
			)
		)
		(property "Manufacturer" "Texas Instruments"
			(at 111.76 288.29 0)
			(effects
				(font
					(size 1.27 1.27)
					(thickness 0.15)
				)
				(justify left bottom)
				(hide yes)
			)
		)
		(property "Author" "Antmicro"
			(at 111.76 290.83 0)
			(effects
				(font
					(size 1.27 1.27)
					(thickness 0.15)
				)
				(justify left bottom)
				(hide yes)
			)
		)
		(property "License" "Apache-2.0"
			(at 111.76 293.37 0)
			(effects
				(font
					(size 1.27 1.27)
					(thickness 0.15)
				)
				(justify left bottom)
				(hide yes)
			)
		)
		(pin "2"
		)
		(pin "4"
		)
		(pin "5"
		)
		(pin "1"
		)
		(pin "6"
		)
		(pin "7"
		)
		(pin "14"
		)
		(pin "8"
		)
		(pin "9"
		)
		(pin "10"
		)
		(pin "11"
		)
		(pin "13"
		)
		(pin "12"
		)
		(pin "3"
		)
		(instances
			(project "sdi-mipi-video-converter"
				(path ""
					(reference "U3")
					(unit 1)
				)
			)
		)
	)
	(symbol
		(lib_id "antmicroResistors0402:R_470R_0402")
		(at 218.44 246.38 90)
		(unit 1)
		(exclude_from_sim no)
		(in_bom yes)
		(on_board yes)
		(dnp no)
		(fields_autoplaced yes)
		(property "Reference" "R14"
			(at 220.98 242.5699 90)
			(effects
				(font
					(size 1.27 1.27)
					(thickness 0.15)
				)
				(justify right)
			)
		)
		(property "Value" "R_470R_0402"
			(at 231.14 226.06 0)
			(effects
				(font
					(size 1.27 1.27)
					(thickness 0.15)
				)
				(justify left bottom)
				(hide yes)
			)
		)
		(property "Footprint" "antmicro-footprints:R_0402_1005Metric"
			(at 233.68 226.06 0)
			(effects
				(font
					(size 1.27 1.27)
					(thickness 0.15)
				)
				(justify left bottom)
				(hide yes)
			)
		)
		(property "Datasheet" "https://www.bourns.com/docs/product-datasheets/cr.pdf"
			(at 236.22 226.06 0)
			(effects
				(font
					(size 1.27 1.27)
					(thickness 0.15)
				)
				(justify left bottom)
				(hide yes)
			)
		)
		(property "Description" "SMD Chip Resistor, 470 ohm, ± 1%, 62.5 mW, 0402 [1005 Metric], Thick Film, General Purpose"
			(at 218.44 246.38 0)
			(effects
				(font
					(size 1.27 1.27)
				)
				(hide yes)
			)
		)
		(property "Manufacturer" "Bourns"
			(at 241.3 226.06 0)
			(effects
				(font
					(size 1.27 1.27)
					(thickness 0.15)
				)
				(justify left bottom)
				(hide yes)
			)
		)
		(property "MPN" "CR0402-FX-4700GLF"
			(at 238.76 226.06 0)
			(effects
				(font
					(size 1.27 1.27)
					(thickness 0.15)
				)
				(justify left bottom)
				(hide yes)
			)
		)
		(property "Val" "470R"
			(at 220.98 245.1099 90)
			(effects
				(font
					(size 1.27 1.27)
					(thickness 0.15)
				)
				(justify right)
			)
		)
		(property "License" "Apache-2.0"
			(at 243.84 226.06 0)
			(effects
				(font
					(size 1.27 1.27)
					(thickness 0.15)
				)
				(justify left bottom)
				(hide yes)
			)
		)
		(property "Author" "Antmicro"
			(at 246.38 226.06 0)
			(effects
				(font
					(size 1.27 1.27)
					(thickness 0.15)
				)
				(justify left bottom)
				(hide yes)
			)
		)
		(property "Tolerance" "1%"
			(at 228.6 226.06 0)
			(effects
				(font
					(size 1.27 1.27)
				)
				(justify left bottom)
				(hide yes)
			)
		)
		(pin "1"
		)
		(pin "2"
		)
		(instances
			(project "sdi-mipi-video-converter"
				(path ""
					(reference "R14")
					(unit 1)
				)
			)
		)
	)
	(symbol
		(lib_id "antmicroDCDCConverters:AP62301_TSOT")
		(at 288.29 72.39 0)
		(unit 1)
		(exclude_from_sim no)
		(in_bom yes)
		(on_board yes)
		(dnp no)
		(fields_autoplaced yes)
		(property "Reference" "U5"
			(at 298.45 64.77 0)
			(effects
				(font
					(size 1.27 1.27)
					(thickness 0.15)
				)
			)
		)
		(property "Value" "AP62301WU-7"
			(at 298.45 67.31 0)
			(effects
				(font
					(size 1.27 1.27)
					(thickness 0.15)
				)
			)
		)
		(property "Footprint" "antmicro-footprints:TSOT23-6"
			(at 323.85 69.85 0)
			(effects
				(font
					(size 1.27 1.27)
					(thickness 0.15)
				)
				(justify left bottom)
				(hide yes)
			)
		)
		(property "Datasheet" "https://www.diodes.com/assets/Datasheets/AP62300_AP62301_AP62300T.pdf"
			(at 323.85 72.39 0)
			(effects
				(font
					(size 1.27 1.27)
					(thickness 0.15)
				)
				(justify left bottom)
				(hide yes)
			)
		)
		(property "Description" "DC-DC Switching Synchronous Buck Regulator, Adjustable, 4.2V-18Vin, 0.8V-7V/3A out, TSOT-26-6"
			(at 288.29 72.39 0)
			(effects
				(font
					(size 1.27 1.27)
				)
				(hide yes)
			)
		)
		(property "MPN" "AP62301WU-7"
			(at 323.85 74.93 0)
			(effects
				(font
					(size 1.27 1.27)
					(thickness 0.15)
				)
				(justify left bottom)
				(hide yes)
			)
		)
		(property "Manufacturer" "Diodes Incorporated"
			(at 323.85 77.47 0)
			(effects
				(font
					(size 1.27 1.27)
					(thickness 0.15)
				)
				(justify left bottom)
				(hide yes)
			)
		)
		(property "Author" "Antmicro"
			(at 323.85 80.01 0)
			(effects
				(font
					(size 1.27 1.27)
					(thickness 0.15)
				)
				(justify left bottom)
				(hide yes)
			)
		)
		(property "License" "Apache-2.0"
			(at 323.85 82.55 0)
			(effects
				(font
					(size 1.27 1.27)
					(thickness 0.15)
				)
				(justify left bottom)
				(hide yes)
			)
		)
		(pin "1"
		)
		(pin "2"
		)
		(pin "3"
		)
		(pin "4"
		)
		(pin "5"
		)
		(pin "6"
		)
		(instances
			(project "sdi-mipi-video-converter"
				(path ""
					(reference "U5")
					(unit 1)
				)
			)
		)
	)
	(symbol
		(lib_id "antmicroResistors0402:R_10k_0402")
		(at 113.03 87.63 90)
		(unit 1)
		(exclude_from_sim no)
		(in_bom yes)
		(on_board yes)
		(dnp no)
		(fields_autoplaced yes)
		(property "Reference" "R98"
			(at 115.57 83.8199 90)
			(effects
				(font
					(size 1.27 1.27)
					(thickness 0.15)
				)
				(justify right)
			)
		)
		(property "Value" "R_10k_0402"
			(at 125.73 67.31 0)
			(effects
				(font
					(size 1.27 1.27)
					(thickness 0.15)
				)
				(justify left bottom)
				(hide yes)
			)
		)
		(property "Footprint" "antmicro-footprints:R_0402_1005Metric"
			(at 128.27 67.31 0)
			(effects
				(font
					(size 1.27 1.27)
					(thickness 0.15)
				)
				(justify left bottom)
				(hide yes)
			)
		)
		(property "Datasheet" "https://www.bourns.com/docs/product-datasheets/cr.pdf"
			(at 130.81 67.31 0)
			(effects
				(font
					(size 1.27 1.27)
					(thickness 0.15)
				)
				(justify left bottom)
				(hide yes)
			)
		)
		(property "Description" "SMD Chip Resistor, 10 kohm, ± 1%, 62.5 mW, 0402 [1005 Metric], Thick Film, General Purpose"
			(at 113.03 87.63 0)
			(effects
				(font
					(size 1.27 1.27)
				)
				(hide yes)
			)
		)
		(property "Manufacturer" "Bourns"
			(at 135.89 67.31 0)
			(effects
				(font
					(size 1.27 1.27)
					(thickness 0.15)
				)
				(justify left bottom)
				(hide yes)
			)
		)
		(property "MPN" "CR0402-FX-1002GLF"
			(at 133.35 67.31 0)
			(effects
				(font
					(size 1.27 1.27)
					(thickness 0.15)
				)
				(justify left bottom)
				(hide yes)
			)
		)
		(property "Val" "10k"
			(at 115.57 86.3599 90)
			(effects
				(font
					(size 1.27 1.27)
					(thickness 0.15)
				)
				(justify right)
			)
		)
		(property "License" "Apache-2.0"
			(at 138.43 67.31 0)
			(effects
				(font
					(size 1.27 1.27)
					(thickness 0.15)
				)
				(justify left bottom)
				(hide yes)
			)
		)
		(property "Author" "Antmicro"
			(at 140.97 67.31 0)
			(effects
				(font
					(size 1.27 1.27)
					(thickness 0.15)
				)
				(justify left bottom)
				(hide yes)
			)
		)
		(property "Tolerance" "1%"
			(at 123.19 67.31 0)
			(effects
				(font
					(size 1.27 1.27)
				)
				(justify left bottom)
				(hide yes)
			)
		)
		(pin "1"
		)
		(pin "2"
		)
		(instances
			(project "sdi-mipi-video-converter"
				(path ""
					(reference "R98")
					(unit 1)
				)
			)
		)
	)
	(symbol
		(lib_id "antmicroResistors0402:R_470R_0402")
		(at 241.3 246.38 90)
		(unit 1)
		(exclude_from_sim no)
		(in_bom yes)
		(on_board yes)
		(dnp no)
		(fields_autoplaced yes)
		(property "Reference" "R18"
			(at 243.84 242.5699 90)
			(effects
				(font
					(size 1.27 1.27)
					(thickness 0.15)
				)
				(justify right)
			)
		)
		(property "Value" "R_470R_0402"
			(at 254 226.06 0)
			(effects
				(font
					(size 1.27 1.27)
					(thickness 0.15)
				)
				(justify left bottom)
				(hide yes)
			)
		)
		(property "Footprint" "antmicro-footprints:R_0402_1005Metric"
			(at 256.54 226.06 0)
			(effects
				(font
					(size 1.27 1.27)
					(thickness 0.15)
				)
				(justify left bottom)
				(hide yes)
			)
		)
		(property "Datasheet" "https://www.bourns.com/docs/product-datasheets/cr.pdf"
			(at 259.08 226.06 0)
			(effects
				(font
					(size 1.27 1.27)
					(thickness 0.15)
				)
				(justify left bottom)
				(hide yes)
			)
		)
		(property "Description" "SMD Chip Resistor, 470 ohm, ± 1%, 62.5 mW, 0402 [1005 Metric], Thick Film, General Purpose"
			(at 241.3 246.38 0)
			(effects
				(font
					(size 1.27 1.27)
				)
				(hide yes)
			)
		)
		(property "Manufacturer" "Bourns"
			(at 264.16 226.06 0)
			(effects
				(font
					(size 1.27 1.27)
					(thickness 0.15)
				)
				(justify left bottom)
				(hide yes)
			)
		)
		(property "MPN" "CR0402-FX-4700GLF"
			(at 261.62 226.06 0)
			(effects
				(font
					(size 1.27 1.27)
					(thickness 0.15)
				)
				(justify left bottom)
				(hide yes)
			)
		)
		(property "Val" "470R"
			(at 243.84 245.1099 90)
			(effects
				(font
					(size 1.27 1.27)
					(thickness 0.15)
				)
				(justify right)
			)
		)
		(property "License" "Apache-2.0"
			(at 266.7 226.06 0)
			(effects
				(font
					(size 1.27 1.27)
					(thickness 0.15)
				)
				(justify left bottom)
				(hide yes)
			)
		)
		(property "Author" "Antmicro"
			(at 269.24 226.06 0)
			(effects
				(font
					(size 1.27 1.27)
					(thickness 0.15)
				)
				(justify left bottom)
				(hide yes)
			)
		)
		(property "Tolerance" "1%"
			(at 251.46 226.06 0)
			(effects
				(font
					(size 1.27 1.27)
				)
				(justify left bottom)
				(hide yes)
			)
		)
		(pin "1"
		)
		(pin "2"
		)
		(instances
			(project "sdi-mipi-video-converter"
				(path ""
					(reference "R18")
					(unit 1)
				)
			)
		)
	)
)
